P  JOB   G:/<user>/9049_F0T_FAN_BOARD_MP5048_D_v02_20221209_0830.brd               
P  CODE  00                                                                     
P  UNITS CUST 0                                                                 
P  TITLE G:/<user>/9049_F0T_FAN_BOARD_MP5048_D_v02_20221209_0830.brd               
P  NUM   001                                                                    
P  REV   A                                                                      
P  VER IPC-D-356A                                                               
C                                                                               
C  IPC-D-356 Ouptut File from Allegro                                           
C  IPC File Date: Mon Dec 12 15:10:19 2022                                      
C                                                                               
C                                                                               
C  Board File:             9049_F0T_FAN_BOARD_MP5048_D_v02_20221209_0830.brd    
C  Design Rule Status:     UP TO DATE                                           
C  Unit of Measure:        mils                                                 
C  Decimal Place Accuracy: 2                                                    
C  Number of etch Layers:  6                                                    
C  Board Thickness(mils):  63.000000                                            
C  Drawing Extents(mils):  -500000  -1000000  4700000  4700000                  
C                                                                               
C                                                                               
C  BOARD LAYER INFORMATION                                                      
C                                                                               
C     Layer      Layer            Layer             Film  Layer                 
C     Name       Material         Type              Type  Number                
C  ---------------------------------------------------------                    
C  TOP           COPPER           CONDUCTOR         POS     1                   
C  GND           COPPER           PLANE             NEG     2                   
C  IN1           COPPER           CONDUCTOR         POS     3                   
C  IN2           COPPER           CONDUCTOR         POS     4                   
C  GND1          COPPER           PLANE             NEG     5                   
C  BOTTOM        COPPER           CONDUCTOR         POS     6                   
C                                                                               
C                                                                               
C  PADSTACK INFORMATION                                                         
C                                                                               
C     Padstack          First     Last                                          
C     Name              Layer     Layer     Width     Height                    
C  ---------------------------------------------------------                    
C  SMD28X32             TOP       TOP            3200      3600                 
C  SMD46X62             TOP       TOP            5000      6600                 
C  SMD11X36             TOP       TOP            1500      4000                 
C  SMD109X109           TOP       TOP           11300     11300                 
C  SMD18X20             TOP       TOP            2200      2400                 
C  SMD87X174            TOP       TOP            9100     17800                 
C  RE-R_0824-2          TOP       TOP            2384      2368                 
C  RE-L_0824-2          TOP       TOP            2384      2368                 
C  C125D125N_T2-0       TOP       BOTTOM        15500     15500                 
C  C85D67_SM85_NPM      TOP       BOTTOM         9700      9700                 
C  C400D252B394X1260_IY TOP       BOTTOM        40400    126700                 
C  BOT355X827D119_197Y- TOP       BOTTOM        35900     83100                 
C  C59D59N              TOP       BOTTOM         8900      8900                 
C  C54D38_T2            TOP       BOTTOM         6800      6800                 
C  S54D38_T2            TOP       BOTTOM         6800      6800                 
C  SMD22X68             TOP       TOP            2600      7200                 
C  SMD16X24             TOP       TOP            2000      2800                 
C  SMD24X24_PM20X20     TOP       TOP            2800      2800                 
C  SMD13X46             TOP       TOP            1700      5000                 
C  SMD24X32             TOP       TOP            2800      3600                 
C  SMD28X36             TOP       TOP            3200      4000                 
C  SMD14X59             TOP       TOP            1800      6300                 
C  SMD107X107           TOP       TOP           11100     11100                 
C  SMD7X32              TOP       TOP            1100      3600                 
C  SMD16X20             TOP       TOP            2000      2400                 
C  SH28X36_CUT_L        TOP       TOP            3156      3944                 
C  SMD7X36              TOP       TOP            1100      4000                 
C  SH28X36_CUT_R        TOP       TOP            3156      3944                 
C  SMD12X99             TOP       TOP            1600     10300                 
C  SH12X95_CUT          TOP       TOP            1582      9848                 
C  SMD95X130            TOP       TOP            9900     13400                 
C  SMD99X130            TOP       TOP           10300     13400                 
C  GF32X197B            BOTTOM    BOTTOM         3600     20100                 
C  GF32X197T            TOP       TOP            3600     20100                 
C  GF173X248B           BOTTOM    BOTTOM        17700     25200                 
C  GF173X248T           TOP       TOP           17700     25200                 
C  SMD22X24             TOP       TOP            2600      2800                 
C  SMD32X34             TOP       TOP            3600      3800                 
C  SMD40X50             TOP       TOP            4400      5400                 
C  VT20D10T30           TOP       BOTTOM         7502      7500                 
C  VT20D10B26           TOP       BOTTOM         7502      7500                 
C  VIA20D10             TOP       BOTTOM         3000      3000                 
C  SPD_C125                                     12500     12500                 
C  SMDC39M118           TOP       TOP           11800     11800                 
C  TP26B                BOTTOM    BOTTOM         7500      7500                 
C  TP30T                TOP       TOP            7500      7500                 
C                                                                               
C                                                                               
C  ****************************************                                     
C     Name mapping for long Signal names                                        
C  ****************************************                                     
C                                                                               
P  NNAMEm0000 P12V_LED_R1_FAN4                                                  
P  NNAMEm0001 P12V_LED_R1_FAN5                                                  
P  NNAMEm0002 P12V_LED_R1_FAN6                                                  
P  NNAMEm0003 P12V_LED_R1_FAN7                                                  
P  NNAMEm0004 P12V_LED_R_FAN7                                                   
P  NNAMEm0005 P12V_LED_R_FAN6                                                   
P  NNAMEm0006 P12V_LED_R_FAN5                                                   
P  NNAMEm0007 P12V_LED_R_FAN4                                                   
P  NNAMEm0008 P12V_LED_R1_FAN3                                                  
P  NNAMEm0009 P12V_LED_R_FAN3                                                   
P  NNAMEm0010 P12V_LED_R1_FAN2                                                  
P  NNAMEm0011 P12V_LED_R_FAN2                                                   
P  NNAMEm0012 P12V_LED_R1_FAN1                                                  
P  NNAMEm0013 P12V_LED_R_FAN1                                                   
P  NNAMEm0014 P12V_LED_R1_FAN0                                                  
P  NNAMEm0015 P12V_LED_R_FAN0                                                   
P  NNAMEm0016 FM_BOARD_SKU_ID2                                                  
P  NNAMEm0017 FM_BOARD_SKU_ID1                                                  
P  NNAMEm0018 FM_BOARD_SKU_ID0                                                  
P  NNAMEm0019 RST_SMB_PDB_R_N                                                   
P  NNAMEm0020 FAN_3_TACH_IL_R1                                                  
P  NNAMEm0021 FAN_3_TACH_OL_R1                                                  
P  NNAMEm0022 FAN_1_TACH_IL_R1                                                  
P  NNAMEm0023 FAN_2_TACH_OL_R1                                                  
P  NNAMEm0024 FAN_1_TACH_OL_R1                                                  
P  NNAMEm0025 FAN_0_TACH_IL_R1                                                  
P  NNAMEm0026 FAN_0_TACH_OL_R1                                                  
P  NNAMEm0027 FAN_2_TACH_IL_R1                                                  
P  NNAMEm0028 SMB_PDBV_FAN_R_U403_SCL                                           
P  NNAMEm0029 SMB_PDBV_FAN_R_U403_SDA                                           
P  NNAMEm0030 FAN_7_TACH_OL_R2                                                  
P  NNAMEm0031 FAN_6_TACH_OL_R2                                                  
P  NNAMEm0032 FAN_7_TACH_IL_R2                                                  
P  NNAMEm0033 FAN_6_TACH_IL_R2                                                  
P  NNAMEm0034 FAN_5_TACH_OL_R2                                                  
P  NNAMEm0035 FAN_4_TACH_OL_R2                                                  
P  NNAMEm0036 FAN_5_TACH_IL_R2                                                  
P  NNAMEm0037 FAN_4_TACH_IL_R2                                                  
P  NNAMEm0038 FAN_3_TACH_OL_R2                                                  
P  NNAMEm0039 FAN_2_TACH_OL_R2                                                  
P  NNAMEm0040 FAN_3_TACH_IL_R2                                                  
P  NNAMEm0041 FAN_2_TACH_IL_R2                                                  
P  NNAMEm0042 FAN_1_TACH_OL_R2                                                  
P  NNAMEm0043 FAN_0_TACH_OL_R2                                                  
P  NNAMEm0044 FAN_1_TACH_IL_R2                                                  
P  NNAMEm0045 FAN_0_TACH_IL_R2                                                  
P  NNAMEm0046 SMB_PDBV_FAN_R_U404_SCL                                           
P  NNAMEm0047 SMB_PDBV_FAN_R_U404_SDA                                           
P  NNAMEm0048 FAN_7_TACH_OL_R1                                                  
P  NNAMEm0049 FAN_6_TACH_OL_R1                                                  
P  NNAMEm0050 FAN_7_TACH_IL_R1                                                  
P  NNAMEm0051 FAN_6_TACH_IL_R1                                                  
P  NNAMEm0052 FAN_5_TACH_OL_R1                                                  
P  NNAMEm0053 FAN_4_TACH_OL_R1                                                  
P  NNAMEm0054 FAN_5_TACH_IL_R1                                                  
P  NNAMEm0055 FAN_4_TACH_IL_R1                                                  
P  NNAMEm0056 FAN_4_OK_LED_R_N                                                  
P  NNAMEm0057 FAN_7_FAIL_LED_R_N                                                
P  NNAMEm0058 FAN_4_FAIL_LED_R_N                                                
P  NNAMEm0059 FAN_6_OK_LED_R_N                                                  
P  NNAMEm0060 FAN_5_FAIL_LED_R_N                                                
P  NNAMEm0061 FAN_7_OK_LED_R_N                                                  
P  NNAMEm0062 FAN_5_OK_LED_R_N                                                  
P  NNAMEm0063 FAN_6_FAIL_LED_R_N                                                
P  NNAMEm0064 FAN_2_FAIL_LED_R_N                                                
P  NNAMEm0065 FAN_0_FAIL_LED_R_N                                                
P  NNAMEm0066 FAN_1_FAIL_LED_R_N                                                
P  NNAMEm0067 FAN_2_OK_LED_R_N                                                  
P  NNAMEm0068 FAN_0_OK_LED_R_N                                                  
P  NNAMEm0069 FAN_1_OK_LED_R_N                                                  
P  NNAMEm0070 FAN_3_FAIL_LED_R_N                                                
P  NNAMEm0071 FAN_3_OK_LED_R_N                                                  
P  NNAMEm0072 U330_FAN FAIL_N                                                   
P  NNAMEm0073 U317_FAN FAIL_N                                                   
P  NNAMEm0074 TDR_SE_50_OHM_TOP                                                 
P  NNAMEm0075 TDR_SE_50_OHM_IN2                                                 
P  NNAMEm0076 TDR_SE_50_OHM_IN1                                                 
P  NNAMEm0077 TDR_SE_50_OHM_BOT                                                 
P  NNAMEm0078 FAN_7_TACH_IL_R                                                   
P  NNAMEm0079 FAN_6_TACH_OL_R                                                   
P  NNAMEm0080 FAN_4_TACH_OL_R                                                   
P  NNAMEm0081 FAN_2_PRESENT_R                                                   
P  NNAMEm0082 FAN_4_TACH_IL_R                                                   
P  NNAMEm0083 FAN_5_TACH_IL_R                                                   
P  NNAMEm0084 MAX31790_U317_ADD0                                                
P  NNAMEm0085 MAX31790_U330_ADD0                                                
P  NNAMEm0086 MAX31790_U330_ADD1                                                
P  NNAMEm0087 FAN_5_TACH_OL_R                                                   
P  NNAMEm0088 SMB_PDBV_FAN_R_U330_SCL                                           
P  NNAMEm0089 FAN_7_PRESENT_R_N                                                 
P  NNAMEm0090 SMB_PDBV_FAN_R_U330_SDA                                           
P  NNAMEm0091 SMB_PDBV_FAN_R_U317_SCL                                           
P  NNAMEm0092 SMB_PDBV_FAN_R_U317_SDA                                           
P  NNAMEm0093 SMB_PDBV_FAN_R_U321_SCL                                           
P  NNAMEm0094 FAN_6_PRESENT_R_N                                                 
P  NNAMEm0095 FAN_0_OK_R_LED_N                                                  
P  NNAMEm0096 SMB_PDBV_FAN_R_U321_SDA                                           
P  NNAMEm0097 FAN_0_TACH_IL_R                                                   
P  NNAMEm0098 FAN_0_TACH_OL_D                                                   
P  NNAMEm0099 FAN_0_TACH_IL_D                                                   
P  NNAMEm0100 FAN_0_TACH_OL_R                                                   
P  NNAMEm0101 FAN_5_PRESENT_R_N                                                 
P  NNAMEm0102 FAN_4_PRSNT_BUF_N                                                 
P  NNAMEm0103 FAN_7_PRSNT_BUF_N                                                 
P  NNAMEm0104 FAN_5_PRSNT_BUF_N                                                 
P  NNAMEm0105 FAN_6_PRSNT_BUF_N                                                 
P  NNAMEm0106 FAN_4_PRESENT_R_N                                                 
P  NNAMEm0107 FAN_3_TACH_OL_R                                                   
P  NNAMEm0108 FAN_0_FAIL_R_LED                                                  
P  NNAMEm0109 FAN_1_FAIL_R_LED                                                  
P  NNAMEm0110 FAN_3_TACH_IL_R                                                   
P  NNAMEm0111 FAN_2_FAIL_R_LED                                                  
P  NNAMEm0112 FAN_3_TACH_OL_D                                                   
P  NNAMEm0113 FAN_3_TACH_IL_D                                                   
P  NNAMEm0114 FAN_5_FAIL_R_LED                                                  
P  NNAMEm0115 FAN_3_FAIL_R_LED                                                  
P  NNAMEm0116 FAN_6_FAIL_R_LED                                                  
P  NNAMEm0117 FAN_3_PRESENT_R_N                                                 
P  NNAMEm0118 FAN_7_FAIL_R_LED                                                  
P  NNAMEm0119 SMB_PDBV_FAN_SDA                                                  
P  NNAMEm0120 FAN_2_TACH_OL_R                                                   
P  NNAMEm0121 FAN_4_FAIL_R_LED                                                  
P  NNAMEm0122 SMB_PDBV_FAN_SCL                                                  
P  NNAMEm0123 FAN_2_TACH_IL_R                                                   
P  NNAMEm0124 FAN_2_TACH_OL_D                                                   
P  NNAMEm0125 FAN_2_TACH_IL_D                                                   
P  NNAMEm0126 FAN_2_PRESENT_R_N                                                 
P  NNAMEm0127 FAN_1_TACH_OL_R                                                   
P  NNAMEm0128 FAN_1_TACH_IL_R                                                   
P  NNAMEm0129 FAN_1_TACH_OL_D                                                   
P  NNAMEm0130 FAN_1_TACH_IL_D                                                   
P  NNAMEm0131 FAN_1_PRESENT_R_N                                                 
P  NNAMEm0132 PD_FAN_BUFF_INPUT_U336E                                           
P  NNAMEm0133 FAN_1_PRESENT_R                                                   
P  NNAMEm0134 FAN_7_FAIL_R_LED_N                                                
P  NNAMEm0135 PD_FAN_BUFF_INPUT_U337F                                           
P  NNAMEm0136 FAN_7_OK_R_LED_N                                                  
P  NNAMEm0137 PD_FAN_BUFF_INPUT_U336F                                           
P  NNAMEm0138 FAN_2_OK_R_LED_N                                                  
P  NNAMEm0139 FAN_2_FAIL_R_LED_N                                                
P  NNAMEm0140 PD_FAN_BUFF_INPUT_U337E                                           
P  NNAMEm0141 FAN_6_FAIL_R_LED_N                                                
P  NNAMEm0142 FAN_6_OK_R_LED_N                                                  
P  NNAMEm0143 FAN_5_FAIL_R_LED_N                                                
P  NNAMEm0144 FAN_5_OK_R_LED_N                                                  
P  NNAMEm0145 FAN_7_TACH_OL_D                                                   
P  NNAMEm0146 FAN_0_FAIL_R_LED_N                                                
P  NNAMEm0147 FAN_7_TACH_IL_D                                                   
P  NNAMEm0148 FAN_4_FAIL_R_LED_N                                                
P  NNAMEm0149 FAN_6_TACH_OL_D                                                   
P  NNAMEm0150 FAN_4_OK_R_LED_N                                                  
P  NNAMEm0151 FAN_7_PRESENT_R                                                   
P  NNAMEm0152 FAN_6_TACH_IL_D                                                   
P  NNAMEm0153 FAN_5_TACH_OL_D                                                   
P  NNAMEm0154 FAN_5_TACH_IL_D                                                   
P  NNAMEm0155 FAN_4_TACH_OL_D                                                   
P  NNAMEm0156 FAN_6_PRESENT_R                                                   
P  NNAMEm0157 FAN_0_PRESENT_R                                                   
P  NNAMEm0158 FAN_4_TACH_IL_D                                                   
P  NNAMEm0159 FAN_3_FAIL_R_LED_N                                                
P  NNAMEm0160 FAN_3_OK_R_LED_N                                                  
P  NNAMEm0161 FAN_5_PRESENT_R                                                   
P  NNAMEm0162 FAN_4_PRESENT_R                                                   
P  NNAMEm0163 FAN_3_PRESENT_R                                                   
P  NNAMEm0164 SMB_PDBV_FAN_R1_IOX_SDA                                           
P  NNAMEm0165 FAN_1_FAIL_R_LED_N                                                
P  NNAMEm0166 P52V_FAN_3_BUFF_EN                                                
P  NNAMEm0167 SMB_PDBV_FAN_R1_IOX_SCL                                           
P  NNAMEm0168 FAN_7_PRSNT_BUF_R_N                                               
P  NNAMEm0169 FAN_1_OK_R_LED_N                                                  
P  NNAMEm0170 P52V_FAN_2_BUFF_EN                                                
P  NNAMEm0171 FAN_6_PRSNT_BUF_R_N                                               
P  NNAMEm0172 P52V_FAN_1_BUFF_EN                                                
P  NNAMEm0173 FAN_5_PRSNT_BUF_R_N                                               
P  NNAMEm0174 MAX31790_U317_PWM_START1                                          
P  NNAMEm0175 P52V_FAN_0_BUFF_EN                                                
P  NNAMEm0176 FAN_4_PRSNT_BUF_R_N                                               
P  NNAMEm0177 P52V_FAN_BUFF_EN_R                                                
P  NNAMEm0178 PD_TCA9548_SML1_U321_A0                                           
P  NNAMEm0179 FAN_7_PRESENT_N                                                   
P  NNAMEm0180 P52V_FAN_7_BUFF_EN                                                
P  NNAMEm0181 PD_TCA9548_SML1_U321_A1                                           
P  NNAMEm0182 FAN_6_PRESENT_N                                                   
P  NNAMEm0183 P52V_FAN_6_BUFF_EN                                                
P  NNAMEm0184 PD_TCA9548_SML1_U321_A2                                           
P  NNAMEm0185 FAN_5_PRESENT_N                                                   
P  NNAMEm0186 P52V_FAN_5_BUFF_EN                                                
P  NNAMEm0187 FAN_4_PRESENT_N                                                   
P  NNAMEm0188 P52V_FAN_4_BUFF_EN                                                
P  NNAMEm0189 P52V_FAN_7_BUFF_EN_R                                              
P  NNAMEm0190 P52V_FAN_6_BUFF_EN_R                                              
P  NNAMEm0191 P52V_FAN_5_BUFF_EN_R                                              
P  NNAMEm0192 P52V_FAN_4_BUFF_EN_R                                              
P  NNAMEm0193 P52V_FAN_3_BUFF_EN_R                                              
P  NNAMEm0194 P52V_FAN_2_BUFF_EN_R                                              
P  NNAMEm0195 P52V_FAN_1_BUFF_EN_R                                              
P  NNAMEm0196 P52V_FAN_0_BUFF_EN_R                                              
P  NNAMEm0197 FAN_3_PRSNT_BUF_N                                                 
P  NNAMEm0198 FAN_1_PRSNT_BUF_N                                                 
P  NNAMEm0199 FAN_0_PRSNT_BUF_N                                                 
P  NNAMEm0200 FAN_2_PRSNT_BUF_N                                                 
P  NNAMEm0201 SMB_PDBV_FAN_R_IOX_SCL                                            
P  NNAMEm0202 FAN_2_PRESENT_N                                                   
P  NNAMEm0203 SMB_PDBV_FAN_R_IOX_SDA                                            
P  NNAMEm0204 FAN_3_PRSNT_BUF_R_N                                               
P  NNAMEm0205 FAN_3_PRESENT_N                                                   
P  NNAMEm0206 FAN_0_PRESENT_R_N                                                 
P  NNAMEm0207 FAN_1_PRESENT_N                                                   
P  NNAMEm0208 FAN_2_PRSNT_BUF_R_N                                               
P  NNAMEm0209 FAN_1_PRSNT_BUF_R_N                                               
P  NNAMEm0210 FAN_0_PRESENT_N                                                   
P  NNAMEm0211 MAX31790_U330_WD_START                                            
P  NNAMEm0212 MAX31790_U330_SPIN_START                                          
P  NNAMEm0213 FAN_0_PRSNT_BUF_R_N                                               
P  NNAMEm0214 MAX31790_U330_FREQ_START                                          
P  NNAMEm0215 MAX31790_U330_PWM_START0                                          
P  NNAMEm0216 MAX31790_U330_PWM_START1                                          
P  NNAMEm0217 MAX31790_U317_WD_START                                            
P  NNAMEm0218 MAX31790_U317_SPIN_START                                          
P  NNAMEm0219 MAX31790_U317_FREQ_START                                          
P  NNAMEm0220 MAX31790_U317_PWM_START0                                          
P  NNAMEm0221 MAX31790_U317_ADD1                                                
P  NNAMEm0222 SMB_PDBV_FAN_R_SDA                                                
P  NNAMEm0223 FAN_7_TACH_OL_R                                                   
P  NNAMEm0224 SMB_PDBV_FAN_R_SCL                                                
P  NNAMEm0225 FAN_6_TACH_IL_R                                                   
C                                                                               
C  ****************************************                                     
C      SIGNAL PINS & VIAS ON THE BOARD                                          
C  ****************************************                                     
C                                                                               
327m0000            VIA   -    M      A01X+002508Y+011900X0300Y         S1      
317m0000            J5    -5    D0380PA00X+002638Y+006461X0540Y    R270 S3      
327m0000            R5704 -2          A01X+002508Y+012400X0180Y0200R180 S1      
327m0001            VIA   -    M      A01X+002488Y+048048X0300Y         S1      
317m0001            J6    -5    D0380PA00X+002638Y+042799X0540Y    R270 S3      
327m0001            R5702 -2          A01X+002758Y+048700X0180Y0200R180 S1      
317m0002            VIA   -    MD0100PA00X+003890Y+080020X0200Y         S0      
327m0002            VIA   -    M      A01X+004800Y+080108X0300Y         S1      
317m0002            J7    -5    D0380PA00X+002638Y+079138X0540Y    R270 S3      
327m0002            R5700 -2          A01X+005350Y+080108X0180Y0200R270 S1      
327m0003            VIA   -    M      A01X+004820Y+116000X0300Y         S1      
327m0003            R5698 -2          A01X+005492Y+116000X0180Y0200     S1      
317m0003            J8    -5    D0380PA00X+002638Y+115476X0540Y    R270 S3      
327m0004            R5697 -2          A01X+005492Y+115600X0180Y0200     S1      
327m0004            R5698 -1          A01X+005808Y+116000X0180Y0200     S1      
327m0005            R5699 -2          A01X+005750Y+080108X0180Y0200R270 S1      
327m0005            R5700 -1          A01X+005350Y+079792X0180Y0200R270 S1      
327m0006            R5702 -1          A01X+002442Y+048700X0180Y0200R180 S1      
327m0006            VIA   -    M      A01X+001970Y+048700X0300Y         S1      
327m0006            R5701 -2          A01X+001508Y+048700X0180Y0200R180 S1      
327m0007            VIA   -    M      A01X+001720Y+012400X0300Y         S1      
327m0007            R5703 -2          A01X+001258Y+012400X0180Y0200R180 S1      
327m0007            R5704 -1          A01X+002192Y+012400X0180Y0200R180 S1      
327m0008            VIA   -    M      A01X+018570Y+011290X0300Y         S1      
317m0008            J4    -5    D0380PA00X+017716Y+008823X0540Y    R090 S3      
327m0008            R5696 -2          A01X+017792Y+012450X0180Y0200     S1      
327m0009            VIA   -    M      A01X+018570Y+012450X0300Y         S1      
327m0009            R5695 -2          A01X+019042Y+012450X0180Y0200     S1      
327m0009            R5696 -1          A01X+018108Y+012450X0180Y0200     S1      
327m0010            VIA   -    M      A01X+018570Y+047620X0300Y         S1      
317m0010            J3    -5    D0380PA00X+017716Y+045161X0540Y    R090 S3      
327m0010            R5694 -2          A01X+017750Y+048692X0180Y0200R090 S1      
327m0011            R5694 -1          A01X+017750Y+049008X0180Y0200R090 S1      
327m0011            R5693 -2          A01X+018150Y+049008X0180Y0200R270 S1      
327m0012            VIA   -    M      A01X+015580Y+077942X0300Y         S1      
327m0012            R5692 -2          A01X+014900Y+077942X0180Y0200R090 S1      
317m0012            VIA   -    MD0100PA00X+017320Y+077080X0200Y         S0      
317m0012            J2    -5    D0380PA00X+017716Y+081500X0540Y    R090 S3      
327m0013            R5691 -2          A01X+014500Y+078258X0180Y0200R270 S1      
327m0013            R5692 -1          A01X+014900Y+078258X0180Y0200R090 S1      
327m0014            VIA   -    M      A01X+015320Y+116950X0300Y         S1      
317m0014            J1    -5    D0380PA00X+017716Y+117839X0540Y    R090 S3      
327m0014            R5690 -2          A01X+014858Y+116950X0180Y0200R180 S1      
327m0015            R5689 -2          A01X+014858Y+116500X0180Y0200R180 S1      
327m0015            R5690 -1          A01X+014542Y+116950X0180Y0200R180 S1      
327TP_U7_PIN20      U7    -20         A01X+005200Y+071234X0140Y0590R270 S1      
317FM_BOARD_ID2     VIA   -    M      A01X+006935Y+071194X0200Y         S2      
017FM_BOARD_ID2     VIA   -    M      A06X+006935Y+071194X0260Y         S2      
017FM_BOARD_ID2           -    MD0100PA00X+006935Y+071194                       
327FM_BOARD_ID2     U7    -19         A01X+005200Y+070978X0140Y0590R270 S1      
327FM_BOARD_ID2     R5685 -2   M      A01X+007092Y+070950X0198Y0197R180 S1      
327FM_BOARD_ID2     R5688 -1          A01X+008042Y+070950X0198Y0197     S1      
327FM_BOARD_ID1     VIA   -    M      A01X+006592Y+070826X0300Y         S1      
327FM_BOARD_ID1     R5687 -1          A01X+008042Y+070400X0198Y0197     S1      
327FM_BOARD_ID1     U7    -18         A01X+005200Y+070722X0140Y0590R270 S1      
327FM_BOARD_ID1     R5684 -2   M      A01X+007092Y+070400X0198Y0197R180 S1      
327FM_BOARD_ID0     VIA   -    M      A01X+006026Y+070466X0300Y         S1      
327FM_BOARD_ID0     R5686 -1          A01X+008042Y+069600X0198Y0197     S1      
327FM_BOARD_ID0     R5683 -2   M      A01X+008042Y+070000X0198Y0197R180 S1      
327FM_BOARD_ID0     U7    -17         A01X+005200Y+070466X0140Y0590R270 S1      
327m0016            R5675 -1          A01X+008042Y+068800X0198Y0197     S1      
327m0016            R5672 -2   M      A01X+008042Y+069200X0198Y0197R180 S1      
327m0016            VIA   -    M      A01X+006561Y+070000X0300Y         S1      
327m0016            U7    -15         A01X+005200Y+069954X0140Y0590R270 S1      
327m0017            R5671 -2   M      A01X+008042Y+068400X0198Y0197R180 S1      
327m0017            R5674 -1          A01X+008042Y+068000X0198Y0197     S1      
317m0017            VIA   -    M      A01X+006000Y+069698X0200Y         S2      
017m0017            VIA   -    M      A06X+006000Y+069698X0260Y         S2      
017m0017                  -    MD0100PA00X+006000Y+069698                       
327m0017            U7    -14         A01X+005200Y+069698X0140Y0590R270 S1      
327m0018            R5670 -2   M      A01X+008042Y+067600X0198Y0197R180 S1      
327m0018            R5673 -1          A01X+008042Y+067200X0198Y0197     S1      
327m0018            VIA   -    M      A01X+006050Y+069350X0300Y         S1      
327m0018            U7    -13         A01X+005200Y+069442X0140Y0590R270 S1      
327U405_D1          R5648 -2          A01X+017808Y+123650X0180Y0200R180 S1      
327U405_D1          C2120 -1          A06X+017600Y+123110X0280Y0320     S2      
317U405_D1          VIA   -    M      A01X+018260Y+122885X0200Y         S2      
017U405_D1          VIA   -    M      A06X+018260Y+122885X0260Y         S2      
017U405_D1                -    MD0100PA00X+018260Y+122885                       
327U405_D1          U405  -D          A01X+018800Y+122885X0240Y0320R180 S1      
327U405_D1          Q9    -G   M      A01X+017700Y+122990X0400Y0500R180 S1      
327m0019            VIA   -    M      A01X+008144Y+057330X0300Y         S1      
327m0019            U321  -3          A01X+008854Y+058700X0140Y0590     S1      
327m0019            R5645 -2          A01X+008000Y+056808X0198Y0197R090 S1      
327U409_D1          R5658 -2   M      A01X+008750Y+013292X0180Y0200R090 S1      
327U409_D1          C2124 -1          A01X+008230Y+012110X0280Y0320     S1      
327U409_D1          VIA   -    M      A01X+009331Y+013292X0300Y         S1      
327U409_D1          U409  -D   M      A01X+008835Y+012350X0240Y0320R090 S1      
327U409_D1          Q13   -G          A01X+008040Y+013350X0400Y0500R090 S1      
327U410_D1          R5659 -2   M      A01X+001658Y+039300X0180Y0200R180 S1      
327U410_D1          U410  -D          A01X+004385Y+038800X0240Y0320R090 S1      
327U410_D1          C2125 -1   M      A01X+003700Y+038460X0280Y0320     S1      
327U410_D1          VIA   -    M      A01X+002982Y+037991X0300Y         S1      
327U410_D1          Q14   -G          A01X+001460Y+038750X0400Y0500R270 S1      
327U411_D1          R5660 -2   M      A01X+007550Y+084642X0180Y0200R090 S1      
327U411_D1          C2126 -1          A01X+007960Y+085850X0280Y0320R270 S1      
317U411_D1          VIA   -    M      A01X+007141Y+084650X0200Y         S2      
017U411_D1          VIA   -    M      A06X+007141Y+084650X0260Y         S2      
017U411_D1                -    MD0100PA00X+007141Y+084650                       
327U411_D1          U411  -D   M      A01X+008085Y+084850X0240Y0320R090 S1      
327U411_D1          Q15   -G          A01X+006440Y+084650X0400Y0500R090 S1      
327U412_D1          R5661 -2          A01X+003608Y+123550X0180Y0200R180 S1      
327U412_D1          VIA   -    M      A01X+004070Y+123560X0300Y         S1      
327U412_D1          C2127 -1          A06X+001710Y+123300X0280Y0320R270 S2      
317U412_D1          VIA   -    MD0100PA00X+001215Y+122785X0200Y         S0      
327U412_D1          Q16   -G   M      A01X+003550Y+122940X0400Y0500R180 S1      
327U412_D1          U412  -D   M      A01X+001550Y+122785X0240Y0320R180 S1      
327U408_D1          R5653 -2   M      A01X+012042Y+014450X0180Y0200     S1      
327U408_D1          Q12   -G          A01X+012210Y+013900X0400Y0500R270 S1      
327U408_D1          U408  -D   M      A01X+011465Y+013150X0240Y0320R270 S1      
327U408_D1          VIA   -    M      A01X+011568Y+013967X0300Y         S1      
327U408_D1          C2123 -1          A01X+011040Y+012100X0280Y0320R090 S1      
327U407_D1          R5652 -2   M      A01X+017900Y+039058X0180Y0200R270 S1      
327U407_D1          C2122 -1   M      A01X+017240Y+038900X0280Y0320R090 S1      
327U407_D1          VIA   -    M      A01X+018361Y+039805X0300Y         S1      
327U407_D1          Q11   -G          A01X+018610Y+039200X0400Y0500R270 S1      
327U407_D1          U407  -D          A01X+016015Y+038900X0240Y0320R270 S1      
327U406_D1          R5649 -2   M      A01X+017900Y+085758X0180Y0200R270 S1      
327U406_D1          C2121 -1          A01X+018500Y+086810X0280Y0320     S1      
327U406_D1          Q10   -G   M      A01X+018560Y+086000X0400Y0500R270 S1      
327U406_D1          U406  -D          A01X+017315Y+085600X0240Y0320R270 S1      
327P12V_LED_FAN7    VIA   -    M      A01X+003720Y+121550X0300Y         S1      
327P12V_LED_FAN7    R5533 -1   M      A01X+006758Y+118400X0180Y0200     S1      
327P12V_LED_FAN7    R5534 -1   M      A01X+006758Y+116800X0180Y0200     S1      
327P12V_LED_FAN7    C2051 -2          A01X+001708Y+121500X0180Y0200R180 S1      
327P12V_LED_FAN7    VIA   -           A01X+002506Y+121554X0300Y         S1      
327P12V_LED_FAN7    C2050 -1          A01X+001900Y+122100X0400Y0500     S1      
327P12V_LED_FAN7    Q16   -D          A01X+003150Y+122060X0400Y0500R180 S1      
327P12V_LED_FAN7    R5697 -1          A01X+005808Y+115600X0180Y0200     S1      
327P12V_LED_FAN6    R5535 -1          A01X+006808Y+080750X0180Y0200     S1      
327P12V_LED_FAN6    R5536 -1          A01X+007458Y+082350X0180Y0200     S1      
327P12V_LED_FAN6    C2039 -2          A01X+001060Y+086292X0180Y0200R090 S1      
317P12V_LED_FAN6    VIA   -    MD0100PA00X+006800Y+080461X0200Y         S0      
317P12V_LED_FAN6    VIA   -    MD0100PA00X+006000Y+079792X0200Y         S0      
327P12V_LED_FAN6    R5699 -1          A01X+005750Y+079792X0180Y0200R270 S1      
327P12V_LED_FAN6    VIA   -    M      A06X+006934Y+075850X0260Y         S2      
317P12V_LED_FAN6    VIA   -    MD0100PA00X+002300Y+076000X0200Y         S0      
317P12V_LED_FAN6    VIA   -    M      A01X+001350Y+086250X0200Y         S2      
017P12V_LED_FAN6    VIA   -    M      A06X+001350Y+086250X0260Y         S2      
017P12V_LED_FAN6          -    MD0100PA00X+001350Y+086250                       
327P12V_LED_FAN6    Q15   -D          A01X+005560Y+085050X0400Y0500R090 S1      
327P12V_LED_FAN6    C2038 -1          A01X+001860Y+086000X0400Y0500R270 S1      
317P12V_LED_FAN6    VIA   -    MD0100PA00X+007700Y+082350X0200Y         S0      
327P12V_LED_FAN3    C2049 -2          A01X+019485Y+014136X0180Y0200R090 S1      
327P12V_LED_FAN3    R5531 -1   M      A01X+013542Y+009700X0180Y0200R180 S1      
327P12V_LED_FAN3    R5532 -1          A01X+013542Y+008100X0180Y0200R180 S1      
317P12V_LED_FAN3    VIA   -    M      A01X+013250Y+009900X0200Y         S2      
017P12V_LED_FAN3    VIA   -    M      A06X+013250Y+009900X0260Y         S2      
017P12V_LED_FAN3          -    MD0100PA00X+013250Y+009900                       
317P12V_LED_FAN3    VIA   -    MD0100PA00X+012750Y+012950X0200Y         S0      
327P12V_LED_FAN3    Q12   -D   M      A01X+013090Y+013500X0400Y0500R270 S1      
317P12V_LED_FAN3    VIA   -    M      A01X+013575Y+013275X0200Y         S2      
017P12V_LED_FAN3    VIA   -    M      A06X+013575Y+013275X0260Y         S2      
017P12V_LED_FAN3          -    MD0100PA00X+013575Y+013275                       
327P12V_LED_FAN3    C2048 -1   M      A01X+018905Y+013863X0400Y0500R270 S1      
327P12V_LED_FAN3    VIA   -    M      A01X+019358Y+012992X0300Y         S1      
327P12V_LED_FAN3    R5695 -1          A01X+019358Y+012450X0180Y0200     S1      
327P12V_LED_FAN4    R5539 -1          A01X+006858Y+008100X0180Y0200     S1      
327P12V_LED_FAN4    R5540 -1   M      A01X+006858Y+009800X0180Y0200     S1      
327P12V_LED_FAN4    C2012 -2          A01X+000890Y+013936X0180Y0200R090 S1      
327P12V_LED_FAN4    R5703 -1          A01X+000942Y+012400X0180Y0200R180 S1      
327P12V_LED_FAN4    VIA   -    M      A01X+000942Y+012900X0300Y         S1      
327P12V_LED_FAN4    C157  -1   M      A01X+001470Y+013753X0400Y0500R270 S1      
327P12V_LED_FAN4    Q13   -D   M      A01X+007160Y+013750X0400Y0500R090 S1      
327P12V_LED_FAN5    R5537 -1          A01X+006808Y+044350X0180Y0200     S1      
327P12V_LED_FAN5    R5538 -1          A01X+006808Y+042700X0180Y0200     S1      
327P12V_LED_FAN5    C2027 -2   M      A01X+001192Y+049100X0180Y0200     S1      
327P12V_LED_FAN5    R5701 -1   M      A01X+001192Y+048700X0180Y0200R180 S1      
327P12V_LED_FAN5    C2026 -1          A01X+001000Y+049650X0400Y0500R180 S1      
327P12V_LED_FAN5    Q14   -D          A01X+002340Y+038350X0400Y0500R270 S1      
317P12V_LED_FAN5    VIA   -    M      A01X+008250Y+039800X0200Y         S2      
017P12V_LED_FAN5    VIA   -    M      A06X+008250Y+039800X0260Y         S2      
017P12V_LED_FAN5          -    MD0100PA00X+008250Y+039800                       
317P12V_LED_FAN5    VIA   -    M      A01X+007050Y+044350X0200Y         S2      
017P12V_LED_FAN5    VIA   -    M      A06X+007050Y+044350X0260Y         S2      
017P12V_LED_FAN5          -    MD0100PA00X+007050Y+044350                       
317P12V_LED_FAN5    VIA   -    M      A01X+007100Y+042700X0200Y         S2      
017P12V_LED_FAN5    VIA   -    M      A06X+007100Y+042700X0260Y         S2      
017P12V_LED_FAN5          -    MD0100PA00X+007100Y+042700                       
327P12V_LED_FAN2    C2037 -2   M      A01X+018692Y+049000X0180Y0200     S1      
327P12V_LED_FAN2    R5529 -1   M      A01X+013642Y+042450X0180Y0200R180 S1      
327P12V_LED_FAN2    R5530 -1          A01X+012442Y+042900X0180Y0200R180 S1      
327P12V_LED_FAN2    VIA   -    M      A01X+018880Y+040830X0300Y         S1      
327P12V_LED_FAN2    VIA   -    M      A01X+015750Y+040018X0300Y         S1      
327P12V_LED_FAN2    Q11   -D          A01X+019490Y+038800X0400Y0500R270 S1      
327P12V_LED_FAN2    C2036 -1          A01X+018450Y+049600X0400Y0500R180 S1      
327P12V_LED_FAN2    R5693 -1   M      A01X+018150Y+048692X0180Y0200R270 S1      
327P12V_LED_FAN1    C2025 -2          A01X+019750Y+086942X0180Y0200R090 S1      
327P12V_LED_FAN1    R5527 -1          A01X+012700Y+080142X0180Y0200R270 S1      
327P12V_LED_FAN1    R5528 -1   M      A01X+013592Y+079080X0180Y0200R180 S1      
327P12V_LED_FAN1    R5691 -1   M      A01X+014500Y+077942X0180Y0200R270 S1      
327P12V_LED_FAN1    VIA   -    M      A01X+019331Y+083961X0300Y         S1      
327P12V_LED_FAN1    C2024 -1          A01X+019200Y+086750X0400Y0500R270 S1      
327P12V_LED_FAN1    Q10   -D   M      A01X+019440Y+085600X0400Y0500R270 S1      
327P12V_LED_FAN1    VIA   -    M      A01X+017380Y+075945X0300Y         S1      
327P12V_LED_FAN0    VIA   -    M      A01X+016280Y+121528X0300Y         S1      
327P12V_LED_FAN0    C2019 -2          A01X+018642Y+121500X0180Y0200     S1      
327P12V_LED_FAN0    R5525 -1   M      A01X+013592Y+115400X0180Y0200R180 S1      
327P12V_LED_FAN0    R5526 -1   M      A01X+013592Y+117000X0180Y0200R180 S1      
327P12V_LED_FAN0    R5689 -1          A01X+014542Y+116500X0180Y0200R180 S1      
327P12V_LED_FAN0    VIA   -    M      A01X+011674Y+116276X0300Y         S1      
327P12V_LED_FAN0    Q9    -D          A01X+017300Y+122110X0400Y0500R180 S1      
327P12V_LED_FAN0    C2018 -1          A01X+018450Y+122100X0400Y0500R180 S1      
327NC_U403_P22      U403  -22         A01X+017202Y+052607X0110Y0360     S1      
327NC_U404_P22      U404  -22         A01X+002543Y+051552X0110Y0360R090 S1      
327NC_U404_P17      U404  -17         A01X+003055Y+052457X0110Y0360     S1      
327NC_U404_P16      U404  -16         A01X+003252Y+052457X0110Y0360     S1      
327NC_U404_P15      U404  -15         A01X+003448Y+052457X0110Y0360     S1      
327NC_U404_P14      U404  -14         A01X+003645Y+052457X0110Y0360     S1      
327NC_U403_P15      U403  -15         A01X+018107Y+051702X0110Y0360R270 S1      
327NC_U403_P14      U403  -14         A01X+018107Y+051505X0110Y0360R270 S1      
327NC_U403_P16      U403  -16         A01X+018107Y+051898X0110Y0360R270 S1      
327NC_U403_P17      U403  -17         A01X+018107Y+052095X0110Y0360R270 S1      
317U403_ADD0        VIA   -    M      A01X+018852Y+051831X0200Y         S2      
017U403_ADD0        VIA   -    M      A06X+018852Y+051831X0260Y         S2      
017U403_ADD0              -    MD0100PA00X+018852Y+051831                       
327U403_ADD0        U403  -18         A01X+018107Y+052292X0110Y0360R270 S1      
327U403_ADD0        R5559 -2          A01X+018842Y+051550X0198Y0197R180 S1      
327U403_ADD0        R5560 -2   M      A01X+018842Y+052100X0198Y0197R180 S1      
327U403_ADD1        VIA   -    M      A01X+017635Y+054012X0300Y         S1      
327U403_ADD1        R5563 -2          A01X+017150Y+053892X0198Y0197R270 S1      
327U403_ADD1        U403  -23         A01X+017005Y+052607X0110Y0360     S1      
327U403_ADD1        R5561 -2   M      A01X+017150Y+053192X0198Y0197R270 S1      
317U403_ADD2        VIA   -    M      A01X+016719Y+052951X0200Y         S2      
017U403_ADD2        VIA   -    M      A06X+016719Y+052951X0260Y         S2      
017U403_ADD2              -    MD0100PA00X+016719Y+052951                       
327U403_ADD2        R5564 -2          A01X+016650Y+053892X0198Y0197R270 S1      
327U403_ADD2        U403  -24         A01X+016808Y+052607X0110Y0360     S1      
327U403_ADD2        R5562 -2   M      A01X+016650Y+053192X0198Y0197R270 S1      
317m0020            VIA   -    M      A01X+014519Y+050423X0200Y         S2      
017m0020            VIA   -    M      A06X+014519Y+050423X0260Y         S2      
017m0020                  -    MD0100PA00X+014519Y+050423                       
327m0020            R5605 -2          A01X+014742Y+050200X0180Y0200     S1      
327m0020            U317  -12         A01X+013187Y+051008X0070Y0320R090 S1      
317FAN_3_PWM_R1     VIA   -    M      A01X+014432Y+049832X0200Y         S2      
017FAN_3_PWM_R1     VIA   -    M      A06X+014432Y+049832X0260Y         S2      
017FAN_3_PWM_R1           -    MD0100PA00X+014432Y+049832                       
327FAN_3_PWM_R1     R5607 -2          A01X+014742Y+049200X0180Y0200     S1      
327FAN_3_PWM_R1     U317  -10         A01X+013187Y+050692X0070Y0320R090 S1      
327m0021            R5608 -2          A01X+014735Y+048700X0180Y0200     S1      
327m0021            VIA   -    M      A01X+014139Y+049635X0300Y         S1      
327m0021            U317  -9          A01X+013187Y+050535X0070Y0320R090 S1      
327m0022            R5599 -2          A01X+014742Y+053200X0180Y0200     S1      
327m0022            VIA   -    M      A01X+014233Y+053200X0300Y         S1      
327m0022            U317  -18         A01X+012400Y+051637X0070Y0320R180 S1      
317m0023            VIA   -    M      A01X+013853Y+050750X0200Y         S2      
017m0023            VIA   -    M      A06X+013853Y+050750X0260Y         S2      
017m0023                  -    MD0100PA00X+013853Y+050750                       
327m0023            R5606 -2          A01X+014742Y+049700X0180Y0200     S1      
327m0023            U317  -11         A01X+013187Y+050850X0070Y0320R090 S1      
317TP_U330_XTAL1    VIA   -           A01X+007565Y+051777X0200Y         S2      
017TP_U330_XTAL1    VIA   -           A06X+007565Y+051777X0260Y         S2      
017TP_U330_XTAL1          -     D0100PA00X+007565Y+051777                       
327TP_U330_XTAL1    U330  -7          A01X+007778Y+051637X0070Y0320     S1      
327m0024            R5602 -2          A01X+014742Y+051700X0180Y0200     S1      
327m0024            VIA   -    M      A01X+013656Y+051936X0300Y         S1      
327m0024            U317  -15         A01X+012872Y+051637X0070Y0320R180 S1      
327TP_U330_XTAL2    VIA   -           A01X+007350Y+052100X0300Y         S1      
327TP_U330_XTAL2    U330  -6          A01X+007935Y+051637X0070Y0320     S1      
327FAN_0_PWM_R1     R5597 -2          A01X+014735Y+054200X0180Y0200     S1      
327FAN_0_PWM_R1     VIA   -    M      A01X+013989Y+054200X0300Y         S1      
327FAN_0_PWM_R1     U317  -20         A01X+012085Y+051637X0070Y0320R180 S1      
327TP_U317_XTAL1    VIA   -           A01X+013600Y+049850X0300Y         S1      
327TP_U317_XTAL1    U317  -7          A01X+012872Y+050063X0070Y0320R180 S1      
327m0025            R5598 -2          A01X+014742Y+053700X0180Y0200     S1      
327m0025            VIA   -    M      A01X+013542Y+053700X0300Y         S1      
327m0025            U317  -19         A01X+012242Y+051637X0070Y0320R180 S1      
327TP_U317_XTAL2    VIA   -           A01X+014150Y+048750X0300Y         S1      
327TP_U317_XTAL2    U317  -6          A01X+012715Y+050063X0070Y0320R180 S1      
327FAN_2_PWM_R1     R5603 -2          A01X+014742Y+051200X0180Y0200     S1      
327FAN_2_PWM_R1     VIA   -    M      A01X+013902Y+051448X0300Y         S1      
327FAN_2_PWM_R1     U317  -14         A01X+013187Y+051322X0070Y0320R090 S1      
327m0026            R5600 -2          A01X+014742Y+052700X0180Y0200     S1      
327m0026            VIA   -    M      A01X+013347Y+052700X0300Y         S1      
327m0026            U317  -17         A01X+012558Y+051637X0070Y0320R180 S1      
327m0027            R5604 -2          A01X+014742Y+050700X0180Y0200     S1      
317m0027            VIA   -    M      A01X+014434Y+050917X0200Y         S2      
017m0027            VIA   -    M      A06X+014434Y+050917X0260Y         S2      
017m0027                  -    MD0100PA00X+014434Y+050917                       
327m0027            U317  -13         A01X+013187Y+051165X0070Y0320R090 S1      
327m0028            VIA   -    M      A01X+018372Y+052929X0300Y         S1      
327m0028            U403  -19         A01X+017792Y+052607X0110Y0360     S1      
327m0028            R5558 -2          A01X+018842Y+052650X0198Y0197R180 S1      
327FAN_1_PWM_R1     R5601 -2          A01X+014742Y+052200X0180Y0200     S1      
327FAN_1_PWM_R1     VIA   -    M      A01X+014206Y+052296X0300Y         S1      
327FAN_1_PWM_R1     U317  -16         A01X+012715Y+051637X0070Y0320R180 S1      
327m0029            VIA   -    M      A01X+018273Y+053509X0300Y         S1      
327m0029            U403  -20         A01X+017595Y+052607X0110Y0360     S1      
327m0029            R5557 -2          A01X+018842Y+053200X0198Y0197R180 S1      
317P52V_FAN_5       J6    -10   D0380PA00X+003425Y+044374X0540Y    R270 S3      
317P52V_FAN_5       J6    -11   D0380PA00X+002638Y+045161X0540Y    R270 S3      
327P52V_FAN_5       C2113 -1          A06X+005800Y+036823X0460Y0620     S2      
327P52V_FAN_5       PD11  -C          A06X+002168Y+036918X0990Y1300R090 S2      
327P52V_FAN_5       C2112 -1          A06X+005800Y+035823X0460Y0620     S2      
327P52V_FAN_5       C2111 -1          A06X+005800Y+034823X0460Y0620     S2      
327P52V_FAN_5       PU7   -12         A06X+006006Y+032344X0070Y0360R180 S2      
327P52V_FAN_5       PU7   -13         A06X+006164Y+032344X0070Y0360R180 S2      
327P52V_FAN_5       PU7   -14         A06X+006321Y+032344X0070Y0360R180 S2      
327P52V_FAN_5       PU7   -15         A06X+006478Y+032344X0276Y0354     S2      
327P52V_FAN_5       PU7   -16         A06X+006222Y+031892X0120Y0990R090 S2      
327P52V_FAN_5       PU7   -9          A06X+005534Y+032344X0070Y0360R180 S2      
327P52V_FAN_5       PU7   -10         A06X+005691Y+032344X0070Y0360R180 S2      
327P52V_FAN_5       PU7   -11         A06X+005848Y+032344X0070Y0360R180 S2      
327P52V_FAN_5       PC43  -1          A06X+006250Y+033930X0400Y0500     S2      
327P52V_FAN_5       VIA   -           A06X+004000Y+033470X0260Y         S2      
327P52V_FAN_5       PU7   -3          A06X+005002Y+031892X0120Y0990R090 S2      
327P52V_FAN_5       PU7   -4          A06X+004746Y+032344X0276Y0354     S2      
327P52V_FAN_5       PU7   -5          A06X+004904Y+032344X0070Y0360R180 S2      
327P52V_FAN_5       PU7   -6          A06X+005061Y+032344X0070Y0360R180 S2      
327P52V_FAN_5       PU7   -7          A06X+005219Y+032344X0070Y0360R180 S2      
327P52V_FAN_5       PU7   -8          A06X+005376Y+032344X0070Y0360R180 S2      
327P52V_FAN_5       PU7   -17         A06X+006222Y+031262X0120Y0990R090 S2      
317P52V_FAN_5       VIA   -    MD0100PA00X+005968Y+031451X0200Y         S0      
317P52V_FAN_5       VIA   -    MD0100PA00X+005968Y+031701X0200Y         S0      
317P52V_FAN_5       VIA   -    MD0100PA00X+006222Y+031701X0200Y         S0      
317P52V_FAN_5       VIA   -    MD0100PA00X+006226Y+031451X0200Y         S0      
317P52V_FAN_5       VIA   -    MD0100PA00X+006476Y+031701X0200Y         S0      
317P52V_FAN_5       VIA   -    MD0100PA00X+006476Y+031451X0200Y         S0      
317P52V_FAN_5       VIA   -    MD0100PA00X+002350Y+036173X0200Y         S0      
317P52V_FAN_5       VIA   -    MD0100PA00X+002050Y+036173X0200Y         S0      
317P52V_FAN_5       VIA   -    MD0100PA00X+005300Y+037000X0200Y    R270 S0      
317P52V_FAN_5       VIA   -    MD0100PA00X+005300Y+036750X0200Y    R270 S0      
317P52V_FAN_5       VIA   -    MD0100PA00X+005300Y+036500X0200Y    R270 S0      
317P52V_FAN_5       VIA   -    M      A01X+002650Y+036173X0300Y         S1      
017P52V_FAN_5       VIA   -    M      A06X+002650Y+036173X0200Y         S1      
017P52V_FAN_5             -    MD0100PA00X+002650Y+036173                       
317P52V_FAN_5       VIA   -    M      A01X+001750Y+036173X0300Y         S1      
017P52V_FAN_5       VIA   -    M      A06X+001750Y+036173X0200Y         S1      
017P52V_FAN_5             -    MD0100PA00X+001750Y+036173                       
317P52V_FAN_5       VIA   -    MD0100PA00X+001750Y+035873X0200Y         S0      
317P52V_FAN_5       VIA   -    MD0100PA00X+002050Y+035873X0200Y         S0      
317P52V_FAN_5       VIA   -    MD0100PA00X+002350Y+035873X0200Y         S0      
317P52V_FAN_5       VIA   -    MD0100PA00X+002650Y+035873X0200Y         S0      
317P52V_FAN_5       VIA   -    MD0100PA00X+005570Y+034250X0200Y         S0      
317P52V_FAN_5       VIA   -    MD0100PA00X+005300Y+035100X0200Y    R270 S0      
317P52V_FAN_5       VIA   -    MD0100PA00X+005300Y+034850X0200Y    R270 S0      
317P52V_FAN_5       VIA   -    MD0100PA00X+005300Y+034600X0200Y    R270 S0      
327P52V_FAN_5       PC42  -1          A01X+004602Y+035830X0870Y1740R090 S1      
327P52V_FAN_5       R5312 -1          A01X+007840Y+041500X0280Y0320R090 S1      
317P52V_FAN_5       VIA   -    MD0100PA00X+008200Y+041500X0200Y         S0      
327P52V_FAN_5       R5313 -1          A01X+007200Y+046310X0280Y0320     S1      
317P52V_FAN_5       VIA   -    MD0100PA00X+007130Y+046000X0200Y         S0      
317P52V_FAN_7       J8    -11   D0380PA00X+002638Y+117839X0540Y    R270 S3      
327P52V_FAN_7       R5320 -1          A01X+007640Y+113400X0280Y0320R090 S1      
317P52V_FAN_7       VIA   -    MD0100PA00X+007950Y+113400X0200Y         S0      
327P52V_FAN_7       C2117 -1          A06X+006027Y+109225X0460Y0620     S2      
327P52V_FAN_7       PD13  -C          A06X+002168Y+109595X0990Y1300R090 S2      
327P52V_FAN_7       PC55  -1          A06X+006465Y+106269X0400Y0500     S2      
327P52V_FAN_7       C2119 -1          A06X+006027Y+108175X0460Y0620     S2      
327P52V_FAN_7       C2118 -1          A06X+006027Y+107125X0460Y0620     S2      
327P52V_FAN_7       PU9   -12         A06X+006056Y+105022X0070Y0360R180 S2      
327P52V_FAN_7       PU9   -13         A06X+006214Y+105022X0070Y0360R180 S2      
327P52V_FAN_7       PU9   -14         A06X+006371Y+105022X0070Y0360R180 S2      
327P52V_FAN_7       PU9   -15         A06X+006528Y+105022X0276Y0354     S2      
327P52V_FAN_7       PU9   -16         A06X+006272Y+104569X0120Y0990R090 S2      
327P52V_FAN_7       PU9   -17         A06X+006272Y+103939X0120Y0990R090 S2      
327P52V_FAN_7       PU9   -9          A06X+005584Y+105022X0070Y0360R180 S2      
327P52V_FAN_7       PU9   -10         A06X+005741Y+105022X0070Y0360R180 S2      
327P52V_FAN_7       PU9   -11         A06X+005898Y+105022X0070Y0360R180 S2      
327P52V_FAN_7       PU9   -3          A06X+005052Y+104569X0120Y0990R090 S2      
327P52V_FAN_7       PU9   -4          A06X+004796Y+105022X0276Y0354     S2      
327P52V_FAN_7       PU9   -5          A06X+004954Y+105022X0070Y0360R180 S2      
327P52V_FAN_7       PU9   -6          A06X+005111Y+105022X0070Y0360R180 S2      
327P52V_FAN_7       PU9   -7          A06X+005269Y+105022X0070Y0360R180 S2      
327P52V_FAN_7       PU9   -8          A06X+005426Y+105022X0070Y0360R180 S2      
317P52V_FAN_7       VIA   -    MD0100PA00X+006018Y+104128X0200Y         S0      
317P52V_FAN_7       VIA   -    MD0100PA00X+006276Y+104128X0200Y         S0      
317P52V_FAN_7       VIA   -    MD0100PA00X+006526Y+104128X0200Y         S0      
317P52V_FAN_7       VIA   -    MD0100PA00X+006526Y+104378X0200Y         S0      
317P52V_FAN_7       VIA   -    MD0100PA00X+006272Y+104378X0200Y         S0      
317P52V_FAN_7       VIA   -    MD0100PA00X+006018Y+104378X0200Y         S0      
317P52V_FAN_7       VIA   -    MD0100PA00X+002500Y+110730X0200Y         S0      
317P52V_FAN_7       VIA   -    MD0100PA00X+002200Y+110730X0200Y         S0      
317P52V_FAN_7       VIA   -    MD0100PA00X+001900Y+110730X0200Y         S0      
317P52V_FAN_7       VIA   -    MD0100PA00X+005564Y+109408X0200Y    R270 S0      
317P52V_FAN_7       VIA   -    MD0100PA00X+005564Y+109066X0200Y    R270 S0      
327P52V_FAN_7       PC54  -1          A01X+004602Y+108507X0870Y1740R090 S1      
317P52V_FAN_7       VIA   -    MD0100PA00X+001900Y+110430X0200Y         S0      
317P52V_FAN_7       VIA   -    MD0100PA00X+002200Y+110430X0200Y         S0      
317P52V_FAN_7       VIA   -    M      A01X+002500Y+110430X0300Y         S1      
017P52V_FAN_7       VIA   -    M      A06X+002500Y+110430X0200Y         S1      
017P52V_FAN_7             -    MD0100PA00X+002500Y+110430                       
317P52V_FAN_7       VIA   -    MD0100PA00X+006103Y+106074X0200Y    R270 S0      
317P52V_FAN_7       VIA   -    MD0100PA00X+006103Y+106415X0200Y    R270 S0      
317P52V_FAN_7       VIA   -    MD0100PA00X+005570Y+106845X0200Y    R270 S0      
317P52V_FAN_7       VIA   -    MD0100PA00X+005570Y+107186X0200Y    R270 S0      
317P52V_FAN_7       VIA   -    MD0100PA00X+005570Y+107588X0200Y    R270 S0      
317P52V_FAN_7       VIA   -    MD0100PA00X+005570Y+107929X0200Y    R270 S0      
317P52V_FAN_7       J8    -10   D0380PA00X+003425Y+117051X0540Y    R270 S3      
327P52V_FAN_7       R5321 -1          A01X+007640Y+119100X0280Y0320R090 S1      
317P52V_FAN_7       VIA   -    MD0100PA00X+007640Y+118810X0200Y         S0      
327P52V_FAN_6       R5316 -1          A01X+007740Y+077800X0280Y0320R090 S1      
317P52V_FAN_6       VIA   -    MD0100PA00X+007740Y+077500X0200Y         S0      
317P52V_FAN_6       VIA   -    MD0100PA00X+008000Y+082850X0200Y         S0      
327P52V_FAN_6       R5317 -1          A01X+007690Y+082850X0280Y0320R090 S1      
327P52V_FAN_6       VIA   -           A06X+006450Y+094350X0260Y         S2      
327P52V_FAN_6       PU8   -3          A06X+002933Y+095431X0120Y0990R270 S2      
327P52V_FAN_6       PU8   -12         A06X+001929Y+094978X0070Y0360     S2      
327P52V_FAN_6       PU8   -13         A06X+001772Y+094978X0070Y0360     S2      
327P52V_FAN_6       PU8   -14         A06X+001614Y+094978X0070Y0360     S2      
327P52V_FAN_6       PU8   -15         A06X+001457Y+094978X0276Y0354R180 S2      
327P52V_FAN_6       PU8   -16         A06X+001713Y+095431X0120Y0990R270 S2      
327P52V_FAN_6       PU8   -17         A06X+001713Y+096061X0120Y0990R270 S2      
327P52V_FAN_6       PU8   -4          A06X+003189Y+094978X0276Y0354R180 S2      
327P52V_FAN_6       PU8   -5          A06X+003032Y+094978X0070Y0360     S2      
327P52V_FAN_6       PU8   -6          A06X+002874Y+094978X0070Y0360     S2      
327P52V_FAN_6       PU8   -7          A06X+002717Y+094978X0070Y0360     S2      
327P52V_FAN_6       PU8   -8          A06X+002559Y+094978X0070Y0360     S2      
327P52V_FAN_6       PU8   -9          A06X+002402Y+094978X0070Y0360     S2      
327P52V_FAN_6       PU8   -10         A06X+002244Y+094978X0070Y0360     S2      
327P52V_FAN_6       PU8   -11         A06X+002087Y+094978X0070Y0360     S2      
327P52V_FAN_6       PC49  -1          A06X+002346Y+093590X0400Y0500R180 S2      
327P52V_FAN_6       C2114 -1          A06X+002783Y+092686X0460Y0620R180 S2      
327P52V_FAN_6       C2116 -1          A06X+002783Y+091636X0460Y0620R180 S2      
327P52V_FAN_6       C2115 -1          A06X+002783Y+090586X0460Y0620R180 S2      
327P52V_FAN_6       PD12  -C          A06X+004061Y+088758X0990Y1300     S2      
317P52V_FAN_6       J7    -11   D0380PA00X+002638Y+081500X0540Y    R270 S3      
317P52V_FAN_6       VIA   -    MD0100PA00X+001459Y+095622X0200Y    R180 S0      
317P52V_FAN_6       VIA   -    MD0100PA00X+001713Y+095622X0200Y    R180 S0      
317P52V_FAN_6       VIA   -    MD0100PA00X+001967Y+095622X0200Y    R180 S0      
317P52V_FAN_6       VIA   -    MD0100PA00X+001967Y+095872X0200Y    R180 S0      
317P52V_FAN_6       VIA   -    MD0100PA00X+001709Y+095872X0200Y    R180 S0      
317P52V_FAN_6       VIA   -    MD0100PA00X+001459Y+095872X0200Y    R180 S0      
317P52V_FAN_6       VIA   -    MD0100PA00X+002759Y+093482X0200Y    R180 S0      
317P52V_FAN_6       VIA   -    M      A01X+002759Y+093782X0300Y    R180 S1      
017P52V_FAN_6       VIA   -    M      A06X+002759Y+093782X0200Y    R180 S1      
017P52V_FAN_6             -    MD0100PA00X+002759Y+093782                       
317P52V_FAN_6       VIA   -    MD0100PA00X+003282Y+091484X0200Y    R180 S0      
317P52V_FAN_6       VIA   -    MD0100PA00X+003282Y+091784X0200Y    R180 S0      
317P52V_FAN_6       VIA   -    MD0100PA00X+003262Y+092824X0200Y    R180 S0      
317P52V_FAN_6       VIA   -    MD0100PA00X+003262Y+092524X0200Y    R180 S0      
317P52V_FAN_6       VIA   -    MD0100PA00X+003252Y+090724X0200Y    R180 S0      
317P52V_FAN_6       VIA   -    MD0100PA00X+003252Y+090424X0200Y    R180 S0      
317P52V_FAN_6       VIA   -    MD0100PA00X+005081Y+088342X0200Y    R090 S0      
317P52V_FAN_6       VIA   -    MD0100PA00X+005081Y+088042X0200Y    R090 S0      
317P52V_FAN_6       VIA   -    MD0100PA00X+005081Y+087742X0200Y    R090 S0      
317P52V_FAN_6       VIA   -    MD0100PA00X+004831Y+088342X0200Y    R090 S0      
317P52V_FAN_6       VIA   -    MD0100PA00X+004831Y+088042X0200Y    R090 S0      
317P52V_FAN_6       VIA   -    MD0100PA00X+004831Y+087742X0200Y    R090 S0      
327P52V_FAN_6       PC48  -1          A01X+006252Y+088000X0870Y1740R270 S1      
317P52V_FAN_6       J7    -10   D0380PA00X+003425Y+080713X0540Y    R270 S3      
327P52V_FAN_4       PU6   -3          A06X+002933Y+022754X0120Y0990R270 S2      
327P52V_FAN_4       PU6   -16         A06X+001713Y+022754X0120Y0990R270 S2      
327P52V_FAN_4       PU6   -17         A06X+001713Y+023384X0120Y0990R270 S2      
327P52V_FAN_4       VIA   -           A06X+006600Y+021680X0260Y         S2      
327P52V_FAN_4       PU6   -12         A06X+001929Y+022301X0070Y0360     S2      
327P52V_FAN_4       PU6   -13         A06X+001772Y+022301X0070Y0360     S2      
327P52V_FAN_4       PU6   -14         A06X+001614Y+022301X0070Y0360     S2      
327P52V_FAN_4       PU6   -15         A06X+001457Y+022301X0276Y0354R180 S2      
327P52V_FAN_4       PU6   -4          A06X+003189Y+022301X0276Y0354R180 S2      
327P52V_FAN_4       PU6   -5          A06X+003032Y+022301X0070Y0360     S2      
327P52V_FAN_4       PU6   -6          A06X+002874Y+022301X0070Y0360     S2      
327P52V_FAN_4       PU6   -7          A06X+002717Y+022301X0070Y0360     S2      
327P52V_FAN_4       PU6   -8          A06X+002559Y+022301X0070Y0360     S2      
327P52V_FAN_4       PU6   -9          A06X+002402Y+022301X0070Y0360     S2      
327P52V_FAN_4       PU6   -10         A06X+002244Y+022301X0070Y0360     S2      
327P52V_FAN_4       PU6   -11         A06X+002087Y+022301X0070Y0360     S2      
327P52V_FAN_4       PC37  -1          A06X+002535Y+020891X0400Y0500R180 S2      
327P52V_FAN_4       C2109 -1          A06X+002980Y+019061X0460Y0620R180 S2      
327P52V_FAN_4       C2108 -1          A06X+002985Y+020031X0460Y0620R180 S2      
327P52V_FAN_4       PD7   -C          A06X+004223Y+016293X0990Y1300     S2      
327P52V_FAN_4       C2110 -1          A06X+002984Y+018080X0460Y0620R180 S2      
317P52V_FAN_4       J5    -10   D0380PA00X+003425Y+008035X0540Y    R270 S3      
327P52V_FAN_4       R5308 -1          A01X+007790Y+006300X0280Y0320R090 S1      
317P52V_FAN_4       VIA   -    MD0100PA00X+008050Y+007400X0200Y         S0      
317P52V_FAN_4       J5    -11   D0380PA00X+002638Y+008823X0540Y    R270 S3      
327P52V_FAN_4       R5309 -1          A01X+007674Y+011950X0280Y0320R090 S1      
317P52V_FAN_4       VIA   -    MD0100PA00X+007674Y+011650X0200Y         S0      
317P52V_FAN_4       VIA   -    MD0100PA00X+001459Y+022944X0200Y    R180 S0      
317P52V_FAN_4       VIA   -    MD0100PA00X+001713Y+022944X0200Y    R180 S0      
317P52V_FAN_4       VIA   -    MD0100PA00X+001967Y+022944X0200Y    R180 S0      
317P52V_FAN_4       VIA   -    MD0100PA00X+001967Y+023194X0200Y    R180 S0      
317P52V_FAN_4       VIA   -    MD0100PA00X+001709Y+023194X0200Y    R180 S0      
317P52V_FAN_4       VIA   -    MD0100PA00X+001459Y+023194X0200Y    R180 S0      
317P52V_FAN_4       VIA   -    MD0100PA00X+003448Y+019924X0200Y    R270 S0      
317P52V_FAN_4       VIA   -    MD0100PA00X+003454Y+018954X0200Y    R270 S0      
317P52V_FAN_4       VIA   -    MD0100PA00X+002919Y+020743X0200Y    R180 S0      
317P52V_FAN_4       VIA   -    M      A01X+002919Y+021043X0300Y    R180 S1      
017P52V_FAN_4       VIA   -    M      A06X+002919Y+021043X0200Y    R180 S1      
017P52V_FAN_4             -    MD0100PA00X+002919Y+021043                       
317P52V_FAN_4       VIA   -    M      A01X+003448Y+020224X0300Y    R270 S1      
017P52V_FAN_4       VIA   -    M      A06X+003448Y+020224X0200Y    R270 S1      
017P52V_FAN_4             -    MD0100PA00X+003448Y+020224                       
317P52V_FAN_4       VIA   -    M      A01X+003454Y+019254X0300Y    R270 S1      
017P52V_FAN_4       VIA   -    M      A06X+003454Y+019254X0200Y    R270 S1      
017P52V_FAN_4             -    MD0100PA00X+003454Y+019254                       
317P52V_FAN_4       VIA   -    M      A01X+004749Y+017426X0200Y    R180 S2      
017P52V_FAN_4       VIA   -    M      A06X+004749Y+017426X0260Y    R180 S2      
017P52V_FAN_4             -    MD0100PA00X+004749Y+017426                       
317P52V_FAN_4       VIA   -    MD0100PA00X+004449Y+017426X0200Y    R180 S0      
317P52V_FAN_4       VIA   -    MD0100PA00X+004449Y+017126X0200Y    R180 S0      
317P52V_FAN_4       VIA   -    MD0100PA00X+004749Y+017126X0200Y    R180 S0      
317P52V_FAN_4       VIA   -    MD0100PA00X+003438Y+017964X0200Y    R270 S0      
317P52V_FAN_4       VIA   -    MD0100PA00X+003438Y+018264X0200Y    R270 S0      
317P52V_FAN_4       VIA   -    MD0100PA00X+004440Y+014686X0200Y    R180 S0      
317P52V_FAN_4       VIA   -    MD0100PA00X+004740Y+014686X0200Y    R180 S0      
317P52V_FAN_4       VIA   -    MD0100PA00X+004740Y+015216X0200Y    R180 S0      
317P52V_FAN_4       VIA   -    MD0100PA00X+004440Y+015216X0200Y    R180 S0      
317P52V_FAN_4       VIA   -    MD0100PA00X+004440Y+014966X0200Y    R180 S0      
317P52V_FAN_4       VIA   -    MD0100PA00X+004740Y+014966X0200Y    R180 S0      
327P52V_FAN_4       PC22  -1          A01X+005782Y+015513X0870Y1740R270 S1      
327P52V_FAN_3       PU3   -3          A06X+015302Y+022754X0120Y0990R270 S2      
327P52V_FAN_3       PU3   -16         A06X+014082Y+022754X0120Y0990R270 S2      
327P52V_FAN_3       PU3   -17         A06X+014082Y+023384X0120Y0990R270 S2      
327P52V_FAN_3       PC36  -1          A06X+017240Y+021590X0400Y0500     S2      
327P52V_FAN_3       VIA   -           A06X+016110Y+021650X0260Y         S2      
327P52V_FAN_3       PU3   -4          A06X+015558Y+022301X0276Y0354R180 S2      
327P52V_FAN_3       PU3   -5          A06X+015401Y+022301X0070Y0360     S2      
327P52V_FAN_3       PU3   -6          A06X+015243Y+022301X0070Y0360     S2      
327P52V_FAN_3       PU3   -7          A06X+015086Y+022301X0070Y0360     S2      
327P52V_FAN_3       PU3   -8          A06X+014928Y+022301X0070Y0360     S2      
327P52V_FAN_3       PU3   -9          A06X+014771Y+022301X0070Y0360     S2      
327P52V_FAN_3       C2107 -1          A06X+017010Y+020740X0460Y0620     S2      
327P52V_FAN_3       PU3   -12         A06X+014298Y+022301X0070Y0360     S2      
327P52V_FAN_3       PU3   -13         A06X+014141Y+022301X0070Y0360     S2      
327P52V_FAN_3       PU3   -14         A06X+013983Y+022301X0070Y0360     S2      
327P52V_FAN_3       PU3   -15         A06X+013826Y+022301X0276Y0354R180 S2      
327P52V_FAN_3       PU3   -10         A06X+014613Y+022301X0070Y0360     S2      
327P52V_FAN_3       PU3   -11         A06X+014456Y+022301X0070Y0360     S2      
327P52V_FAN_3       C2106 -1          A06X+017020Y+018750X0460Y0620     S2      
327P52V_FAN_3       C2105 -1          A06X+017020Y+019750X0460Y0620     S2      
327P52V_FAN_3       PD10  -C          A06X+015621Y+016963X0990Y1300R180 S2      
317P52V_FAN_3       J4    -10   D0380PA00X+016929Y+007248X0540Y    R090 S3      
317P52V_FAN_3       J4    -11   D0380PA00X+017716Y+006461X0540Y    R090 S3      
317P52V_FAN_3       VIA   -    MD0100PA00X+012350Y+005950X0200Y         S0      
327P52V_FAN_3       R5325 -1          A01X+012660Y+005950X0280Y0320R270 S1      
317P52V_FAN_3       VIA   -    MD0100PA00X+012250Y+010200X0200Y         S0      
327P52V_FAN_3       R5324 -1          A01X+012250Y+010510X0280Y0320     S1      
317P52V_FAN_3       VIA   -    MD0100PA00X+013824Y+022944X0200Y    R180 S0      
317P52V_FAN_3       VIA   -    MD0100PA00X+014082Y+022944X0200Y    R180 S0      
317P52V_FAN_3       VIA   -    MD0100PA00X+014336Y+022944X0200Y    R180 S0      
317P52V_FAN_3       VIA   -    MD0100PA00X+014336Y+023194X0200Y    R180 S0      
317P52V_FAN_3       VIA   -    MD0100PA00X+014078Y+023194X0200Y    R180 S0      
317P52V_FAN_3       VIA   -    MD0100PA00X+013820Y+023194X0200Y    R180 S0      
317P52V_FAN_3       VIA   -    MD0100PA00X+016856Y+021454X0200Y    R090 S0      
317P52V_FAN_3       VIA   -    MD0100PA00X+016856Y+021754X0200Y    R090 S0      
317P52V_FAN_3       VIA   -    MD0100PA00X+016486Y+020544X0200Y    R090 S0      
317P52V_FAN_3       VIA   -    M      A01X+016486Y+020844X0300Y    R090 S1      
017P52V_FAN_3       VIA   -    M      A06X+016486Y+020844X0200Y    R090 S1      
017P52V_FAN_3             -    MD0100PA00X+016486Y+020844                       
317P52V_FAN_3       VIA   -    MD0100PA00X+016496Y+019654X0200Y    R090 S0      
317P52V_FAN_3       VIA   -    M      A01X+016496Y+019954X0300Y    R090 S1      
017P52V_FAN_3       VIA   -    M      A06X+016496Y+019954X0200Y    R090 S1      
017P52V_FAN_3             -    MD0100PA00X+016496Y+019954                       
317P52V_FAN_3       VIA   -    M      A01X+016516Y+018914X0300Y    R090 S1      
017P52V_FAN_3       VIA   -    M      A06X+016516Y+018914X0200Y    R090 S1      
017P52V_FAN_3             -    MD0100PA00X+016516Y+018914                       
317P52V_FAN_3       VIA   -    MD0100PA00X+016516Y+018614X0200Y    R090 S0      
317P52V_FAN_3       VIA   -    MD0100PA00X+014966Y+016544X0200Y    R090 S0      
317P52V_FAN_3       VIA   -    MD0100PA00X+014966Y+016844X0200Y    R090 S0      
317P52V_FAN_3       VIA   -    MD0100PA00X+014966Y+017144X0200Y    R090 S0      
317P52V_FAN_3       VIA   -    MD0100PA00X+014966Y+017444X0200Y    R090 S0      
317P52V_FAN_3       VIA   -    MD0100PA00X+015458Y+014915X0200Y    R180 S0      
317P52V_FAN_3       VIA   -    MD0100PA00X+015458Y+014665X0200Y    R180 S0      
317P52V_FAN_3       VIA   -    MD0100PA00X+014858Y+014915X0200Y    R180 S0      
317P52V_FAN_3       VIA   -    MD0100PA00X+015158Y+014915X0200Y    R180 S0      
317P52V_FAN_3       VIA   -    MD0100PA00X+015158Y+014665X0200Y    R180 S0      
317P52V_FAN_3       VIA   -    MD0100PA00X+014858Y+014665X0200Y    R180 S0      
327P52V_FAN_3       PC35  -1          A01X+014563Y+015513X0870Y1740R090 S1      
327P52V_FAN_0       R5300 -1          A01X+012510Y+119250X0280Y0320R270 S1      
317P52V_FAN_0       VIA   -    MD0100PA00X+012300Y+118100X0200Y         S0      
327P52V_FAN_0       PD1   -C          A06X+018380Y+109599X0990Y1300R090 S2      
327P52V_FAN_0       C2098 -1          A06X+013750Y+108810X0460Y0620R180 S2      
327P52V_FAN_0       C2096 -1          A06X+013750Y+109860X0460Y0620R180 S2      
327P52V_FAN_0       PC1   -1          A06X+013800Y+106900X0400Y0500R180 S2      
327P52V_FAN_0       C2097 -1          A06X+013750Y+107760X0460Y0620R180 S2      
327P52V_FAN_0       PU1   -13         A06X+017093Y+105022X0070Y0360R180 S2      
327P52V_FAN_0       PU1   -14         A06X+017251Y+105022X0070Y0360R180 S2      
327P52V_FAN_0       PU1   -15         A06X+017408Y+105022X0276Y0354     S2      
327P52V_FAN_0       PU1   -3          A06X+015932Y+104569X0120Y0990R090 S2      
327P52V_FAN_0       PU1   -12         A06X+016936Y+105022X0070Y0360R180 S2      
327P52V_FAN_0       PU1   -16         A06X+017152Y+104569X0120Y0990R090 S2      
327P52V_FAN_0       PU1   -17         A06X+017152Y+103939X0120Y0990R090 S2      
327P52V_FAN_0       PU1   -4          A06X+015676Y+105022X0276Y0354     S2      
327P52V_FAN_0       PU1   -5          A06X+015833Y+105022X0070Y0360R180 S2      
327P52V_FAN_0       PU1   -6          A06X+015991Y+105022X0070Y0360R180 S2      
327P52V_FAN_0       PU1   -7          A06X+016148Y+105022X0070Y0360R180 S2      
327P52V_FAN_0       PU1   -8          A06X+016306Y+105022X0070Y0360R180 S2      
327P52V_FAN_0       PU1   -9          A06X+016463Y+105022X0070Y0360R180 S2      
327P52V_FAN_0       PU1   -10         A06X+016621Y+105022X0070Y0360R180 S2      
327P52V_FAN_0       PU1   -11         A06X+016778Y+105022X0070Y0360R180 S2      
317P52V_FAN_0       VIA   -    MD0100PA00X+016898Y+104128X0200Y         S0      
317P52V_FAN_0       VIA   -    MD0100PA00X+017156Y+104128X0200Y         S0      
317P52V_FAN_0       VIA   -    MD0100PA00X+017406Y+104128X0200Y         S0      
317P52V_FAN_0       VIA   -    MD0100PA00X+017406Y+104378X0200Y         S0      
317P52V_FAN_0       VIA   -    MD0100PA00X+017152Y+104378X0200Y         S0      
317P52V_FAN_0       VIA   -    MD0100PA00X+016898Y+104378X0200Y         S0      
317P52V_FAN_0       VIA   -    MD0100PA00X+018346Y+110666X0200Y         S0      
317P52V_FAN_0       VIA   -    MD0100PA00X+018046Y+110666X0200Y         S0      
317P52V_FAN_0       VIA   -    M      A01X+018646Y+110666X0200Y         S2      
017P52V_FAN_0       VIA   -    M      A06X+018646Y+110666X0260Y         S2      
017P52V_FAN_0             -    MD0100PA00X+018646Y+110666                       
317P52V_FAN_0       VIA   -    MD0100PA00X+018046Y+110366X0200Y         S0      
317P52V_FAN_0       VIA   -    MD0100PA00X+018346Y+110366X0200Y         S0      
317P52V_FAN_0       VIA   -    MD0100PA00X+018646Y+110366X0200Y         S0      
317P52V_FAN_0       VIA   -    MD0100PA00X+014307Y+109750X0200Y    R270 S0      
317P52V_FAN_0       VIA   -    MD0100PA00X+014307Y+109500X0200Y    R270 S0      
317P52V_FAN_0       VIA   -    MD0100PA00X+014307Y+109250X0200Y    R270 S0      
327P52V_FAN_0       PC7   -1          A01X+015502Y+108507X0870Y1740R270 S1      
317P52V_FAN_0       VIA   -    MD0100PA00X+014157Y+107040X0200Y    R270 S0      
317P52V_FAN_0       VIA   -    MD0100PA00X+014157Y+106790X0200Y    R270 S0      
317P52V_FAN_0       VIA   -    MD0100PA00X+014307Y+107800X0200Y    R270 S0      
317P52V_FAN_0       VIA   -    MD0100PA00X+014307Y+107550X0200Y    R270 S0      
317P52V_FAN_0       VIA   -    MD0100PA00X+014307Y+107300X0200Y    R270 S0      
327P52V_FAN_0       R5301 -1          A01X+012660Y+113750X0280Y0320R270 S1      
317P52V_FAN_0       VIA   -    MD0100PA00X+012350Y+113750X0200Y         S0      
317P52V_FAN_0       J1    -10   D0380PA00X+016929Y+116264X0540Y    R090 S3      
317P52V_FAN_0       J1    -11   D0380PA00X+017716Y+115476X0540Y    R090 S3      
317P52V_FAN_2       J3    -10   D0380PA00X+016929Y+043587X0540Y    R090 S3      
317P52V_FAN_2       J3    -11   D0380PA00X+017716Y+042799X0540Y    R090 S3      
327P52V_FAN_2       VIA   -           A06X+018980Y+038030X0260Y         S2      
327P52V_FAN_2       PD9   -C          A06X+018186Y+036918X0990Y1300R090 S2      
327P52V_FAN_2       C2103 -1          A06X+014420Y+036803X0460Y0620R180 S2      
317P52V_FAN_2       VIA   -    MD0100PA00X+011750Y+039850X0200Y         S0      
327P52V_FAN_2       R5329 -1          A01X+012688Y+039950X0280Y0320R270 S1      
327P52V_FAN_2       C2104 -1          A06X+014420Y+035803X0460Y0620R180 S2      
327P52V_FAN_2       C2102 -1          A06X+014420Y+034803X0460Y0620R180 S2      
327P52V_FAN_2       PU5   -13         A06X+017093Y+032344X0070Y0360R180 S2      
327P52V_FAN_2       PU5   -14         A06X+017251Y+032344X0070Y0360R180 S2      
327P52V_FAN_2       PU5   -15         A06X+017408Y+032344X0276Y0354     S2      
327P52V_FAN_2       PU5   -3          A06X+015932Y+031892X0120Y0990R090 S2      
327P52V_FAN_2       PU5   -12         A06X+016936Y+032344X0070Y0360R180 S2      
327P52V_FAN_2       PU5   -16         A06X+017152Y+031892X0120Y0990R090 S2      
327P52V_FAN_2       PU5   -4          A06X+015676Y+032344X0276Y0354     S2      
327P52V_FAN_2       PU5   -5          A06X+015833Y+032344X0070Y0360R180 S2      
327P52V_FAN_2       PU5   -6          A06X+015991Y+032344X0070Y0360R180 S2      
327P52V_FAN_2       PU5   -7          A06X+016148Y+032344X0070Y0360R180 S2      
327P52V_FAN_2       PU5   -8          A06X+016306Y+032344X0070Y0360R180 S2      
327P52V_FAN_2       PU5   -9          A06X+016463Y+032344X0070Y0360R180 S2      
327P52V_FAN_2       PU5   -10         A06X+016621Y+032344X0070Y0360R180 S2      
327P52V_FAN_2       PU5   -11         A06X+016778Y+032344X0070Y0360R180 S2      
327P52V_FAN_2       PC30  -1          A06X+014100Y+033900X0400Y0500R180 S2      
327P52V_FAN_2       PU5   -17         A06X+017152Y+031262X0120Y0990R090 S2      
317P52V_FAN_2       VIA   -    MD0100PA00X+016898Y+031701X0200Y         S0      
317P52V_FAN_2       VIA   -    MD0100PA00X+017152Y+031701X0200Y         S0      
317P52V_FAN_2       VIA   -    MD0100PA00X+017406Y+031701X0200Y         S0      
317P52V_FAN_2       VIA   -    MD0100PA00X+017406Y+031451X0200Y         S0      
317P52V_FAN_2       VIA   -    MD0100PA00X+017156Y+031451X0200Y         S0      
317P52V_FAN_2       VIA   -    MD0100PA00X+016898Y+031451X0200Y         S0      
317P52V_FAN_2       VIA   -    MD0100PA00X+017986Y+036229X0200Y         S0      
317P52V_FAN_2       VIA   -    MD0100PA00X+017986Y+035979X0200Y         S0      
317P52V_FAN_2       VIA   -    MD0100PA00X+018586Y+036229X0200Y         S0      
317P52V_FAN_2       VIA   -    MD0100PA00X+018286Y+036229X0200Y         S0      
317P52V_FAN_2       VIA   -    MD0100PA00X+018286Y+035979X0200Y         S0      
317P52V_FAN_2       VIA   -    MD0100PA00X+018586Y+035979X0200Y         S0      
317P52V_FAN_2       VIA   -    MD0100PA00X+017686Y+036229X0200Y         S0      
317P52V_FAN_2       VIA   -    MD0100PA00X+017686Y+035979X0200Y         S0      
317P52V_FAN_2       VIA   -    MD0100PA00X+014990Y+036430X0200Y         S0      
317P52V_FAN_2       VIA   -    MD0100PA00X+014990Y+036753X0200Y         S0      
317P52V_FAN_2       VIA   -    MD0100PA00X+014990Y+037030X0200Y         S0      
317P52V_FAN_2       VIA   -    MD0100PA00X+014460Y+033983X0200Y         S0      
317P52V_FAN_2       VIA   -    MD0100PA00X+014460Y+033710X0200Y         S0      
317P52V_FAN_2       VIA   -    MD0100PA00X+014990Y+035180X0200Y         S0      
317P52V_FAN_2       VIA   -    MD0100PA00X+014990Y+034903X0200Y         S0      
317P52V_FAN_2       VIA   -    MD0100PA00X+014990Y+034630X0200Y         S0      
327P52V_FAN_2       PC29  -1          A01X+015642Y+035810X0870Y1740R270 S1      
317P52V_FAN_2       VIA   -    M      A01X+015886Y+033223X0200Y         S2      
017P52V_FAN_2       VIA   -    M      A06X+015886Y+033223X0260Y         S2      
017P52V_FAN_2             -    MD0100PA00X+015886Y+033223                       
317P52V_FAN_2       VIA   -    MD0100PA00X+015886Y+032923X0200Y         S0      
327P52V_FAN_2       R5328 -1          A01X+012510Y+046100X0280Y0320R270 S1      
317P52V_FAN_2       VIA   -    MD0100PA00X+012200Y+046300X0200Y         S0      
327P52V_FAN_1       PU4   -3          A06X+015302Y+095746X0120Y0990R270 S2      
327P52V_FAN_1       PU4   -4          A06X+015558Y+095293X0276Y0354R180 S2      
327P52V_FAN_1       PU4   -5          A06X+015401Y+095293X0070Y0360     S2      
327P52V_FAN_1       PU4   -6          A06X+015243Y+095293X0070Y0360     S2      
327P52V_FAN_1       PU4   -7          A06X+015086Y+095293X0070Y0360     S2      
327P52V_FAN_1       PU4   -8          A06X+014928Y+095293X0070Y0360     S2      
327P52V_FAN_1       PU4   -9          A06X+014771Y+095293X0070Y0360     S2      
327P52V_FAN_1       PU4   -12         A06X+014298Y+095293X0070Y0360     S2      
327P52V_FAN_1       PU4   -13         A06X+014141Y+095293X0070Y0360     S2      
327P52V_FAN_1       PU4   -14         A06X+013983Y+095293X0070Y0360     S2      
327P52V_FAN_1       PU4   -15         A06X+013826Y+095293X0276Y0354R180 S2      
327P52V_FAN_1       PU4   -16         A06X+014082Y+095746X0120Y0990R270 S2      
327P52V_FAN_1       PU4   -17         A06X+014082Y+096376X0120Y0990R270 S2      
327P52V_FAN_1       PU4   -10         A06X+014613Y+095293X0070Y0360     S2      
327P52V_FAN_1       PU4   -11         A06X+014456Y+095293X0070Y0360     S2      
327P52V_FAN_1       PC24  -1          A06X+017218Y+094160X0400Y0500     S2      
327P52V_FAN_1       C2101 -1          A06X+016770Y+093277X0460Y0620     S2      
327P52V_FAN_1       C2100 -1          A06X+016770Y+092250X0460Y0620     S2      
327P52V_FAN_1       C2099 -1          A06X+016770Y+091200X0460Y0620     S2      
327P52V_FAN_1       PD8   -C          A06X+016011Y+089320X0990Y1300R180 S2      
327P52V_FAN_1       R5305 -1          A01X+013210Y+076650X0280Y0320R270 S1      
317P52V_FAN_1       VIA   -    M      A01X+013390Y+077600X0200Y         S2      
017P52V_FAN_1       VIA   -    M      A06X+013390Y+077600X0260Y         S2      
017P52V_FAN_1             -    MD0100PA00X+013390Y+077600                       
317P52V_FAN_1       J2    -10   D0380PA00X+016929Y+079925X0540Y    R090 S3      
317P52V_FAN_1       J2    -11   D0380PA00X+017716Y+079138X0540Y    R090 S3      
327P52V_FAN_1       R5304 -1          A01X+012610Y+082911X0280Y0320R270 S1      
317P52V_FAN_1       VIA   -    MD0100PA00X+012300Y+082911X0200Y         S0      
317P52V_FAN_1       VIA   -    MD0100PA00X+013828Y+095936X0200Y    R180 S0      
317P52V_FAN_1       VIA   -    MD0100PA00X+014082Y+095936X0200Y    R180 S0      
317P52V_FAN_1       VIA   -    MD0100PA00X+014336Y+095936X0200Y    R180 S0      
317P52V_FAN_1       VIA   -    MD0100PA00X+014336Y+096186X0200Y    R180 S0      
317P52V_FAN_1       VIA   -    MD0100PA00X+014078Y+096186X0200Y    R180 S0      
317P52V_FAN_1       VIA   -    MD0100PA00X+013828Y+096186X0200Y    R180 S0      
317P52V_FAN_1       VIA   -    MD0100PA00X+016818Y+094310X0200Y    R180 S0      
317P52V_FAN_1       VIA   -    MD0100PA00X+016818Y+094010X0200Y    R180 S0      
317P52V_FAN_1       VIA   -    MD0100PA00X+016288Y+091350X0200Y    R180 S0      
317P52V_FAN_1       VIA   -    MD0100PA00X+016288Y+092450X0200Y    R180 S0      
317P52V_FAN_1       VIA   -    MD0100PA00X+016288Y+092150X0200Y    R180 S0      
317P52V_FAN_1       VIA   -    MD0100PA00X+016288Y+093450X0200Y    R180 S0      
317P52V_FAN_1       VIA   -    MD0100PA00X+016288Y+093150X0200Y    R180 S0      
317P52V_FAN_1       VIA   -    MD0100PA00X+016288Y+091050X0200Y    R180 S0      
317P52V_FAN_1       VIA   -    MD0100PA00X+014986Y+089612X0200Y    R090 S0      
317P52V_FAN_1       VIA   -    MD0100PA00X+014986Y+089312X0200Y    R090 S0      
317P52V_FAN_1       VIA   -    MD0100PA00X+014986Y+089012X0200Y    R090 S0      
317P52V_FAN_1       VIA   -    MD0100PA00X+015236Y+089612X0200Y    R090 S0      
317P52V_FAN_1       VIA   -    MD0100PA00X+015236Y+089312X0200Y    R090 S0      
317P52V_FAN_1       VIA   -    MD0100PA00X+015236Y+089012X0200Y    R090 S0      
327P52V_FAN_1       PC23  -1          A01X+014188Y+088340X0870Y1740R090 S1      
327m0030            R5596 -2          A01X+005385Y+053600X0180Y0200     S1      
327m0030            VIA   -    M      A01X+004786Y+053458X0300Y         S1      
327m0030            U404  -13         A01X+003842Y+052457X0110Y0360     S1      
327FAN_7_PWM_R2     R5595 -2          A01X+005378Y+053100X0180Y0200     S1      
327FAN_7_PWM_R2     VIA   -    M      A01X+004345Y+052817X0300Y         S1      
327FAN_7_PWM_R2     U404  -12         A01X+004157Y+052142X0110Y0360R090 S1      
327m0031            R5594 -2          A01X+005378Y+052600X0180Y0200     S1      
327m0031            VIA   -    M      A01X+004912Y+052600X0300Y         S1      
327m0031            U404  -11         A01X+004157Y+051945X0110Y0360R090 S1      
327m0032            R5593 -2          A01X+005378Y+052100X0180Y0200     S1      
327m0032            VIA   -    M      A01X+004850Y+051985X0300Y         S1      
327m0032            U404  -10         A01X+004157Y+051748X0110Y0360R090 S1      
327m0033            R5592 -2          A01X+005378Y+051600X0180Y0200     S1      
327m0033            VIA   -    M      A01X+004714Y+051286X0300Y         S1      
327m0033            U404  -8          A01X+004157Y+051355X0110Y0360R090 S1      
327FAN_6_PWM_R2     R5591 -2          A01X+005378Y+051100X0180Y0200     S1      
327FAN_6_PWM_R2     VIA   -    M      A01X+004897Y+050770X0300Y         S1      
327FAN_6_PWM_R2     U404  -7          A01X+004157Y+051158X0110Y0360R090 S1      
327m0034            R5590 -2          A01X+005378Y+050600X0180Y0200     S1      
327m0034            VIA   -    M      A01X+004414Y+050506X0300Y         S1      
327m0034            U404  -6          A01X+003842Y+050843X0110Y0360     S1      
327FAN_5_PWM_R2     R5589 -2          A01X+005378Y+050050X0180Y0200     S1      
327FAN_5_PWM_R2     VIA   -    M      A01X+004887Y+050050X0300Y         S1      
327FAN_5_PWM_R2     U404  -5          A01X+003645Y+050843X0110Y0360     S1      
327m0035            R5588 -2          A01X+005378Y+049550X0180Y0200     S1      
327m0035            VIA   -    M      A01X+004595Y+049550X0300Y         S1      
327m0035            U404  -4          A01X+003448Y+050843X0110Y0360     S1      
327m0036            R5587 -2          A01X+005378Y+049050X0180Y0200     S1      
327m0036            VIA   -    M      A01X+004902Y+049050X0300Y         S1      
327m0036            U404  -3          A01X+003252Y+050843X0110Y0360     S1      
327m0037            R5586 -2          A01X+005378Y+048550X0180Y0200     S1      
327m0037            VIA   -    M      A01X+004120Y+048975X0300Y         S1      
327m0037            U404  -2          A01X+003055Y+050843X0110Y0360     S1      
327FAN_4_PWM_R2     R5585 -2          A01X+005385Y+048050X0180Y0200     S1      
327FAN_4_PWM_R2     VIA   -    M      A01X+004822Y+048050X0300Y         S1      
327FAN_4_PWM_R2     U404  -1          A01X+002858Y+050843X0110Y0360     S1      
327m0038            R5584 -2          A01X+015365Y+048700X0180Y0200R180 S1      
327m0038            VIA   -    M      A01X+015983Y+048700X0300Y         S1      
327m0038            U403  -13         A01X+018107Y+051308X0110Y0360R270 S1      
327FAN_3_PWM_R2     R5583 -2          A01X+015372Y+049200X0180Y0200R180 S1      
327FAN_3_PWM_R2     VIA   -    M      A01X+016530Y+049200X0300Y         S1      
327FAN_3_PWM_R2     U403  -12         A01X+017792Y+050993X0110Y0360     S1      
327m0039            R5582 -2          A01X+015372Y+049700X0180Y0200R180 S1      
327m0039            VIA   -    M      A01X+015968Y+049700X0300Y         S1      
327m0039            U403  -11         A01X+017595Y+050993X0110Y0360     S1      
327m0040            R5581 -2          A01X+015372Y+050200X0180Y0200R180 S1      
327m0040            VIA   -    M      A01X+016663Y+050200X0300Y         S1      
327m0040            U403  -10         A01X+017398Y+050993X0110Y0360     S1      
327m0041            R5580 -2          A01X+015372Y+050700X0180Y0200R180 S1      
327m0041            VIA   -    M      A01X+016222Y+050548X0300Y         S1      
327m0041            U403  -8          A01X+017005Y+050993X0110Y0360     S1      
327FAN_2_PWM_R2     R5579 -2          A01X+015372Y+051200X0180Y0200R180 S1      
327FAN_2_PWM_R2     VIA   -    M      A01X+015857Y+050993X0300Y         S1      
327FAN_2_PWM_R2     U403  -7          A01X+016808Y+050993X0110Y0360     S1      
317m0042            VIA   -    M      A01X+015372Y+051450X0200Y         S2      
017m0042            VIA   -    M      A06X+015372Y+051450X0260Y         S2      
017m0042                  -    MD0100PA00X+015372Y+051450                       
327m0042            R5578 -2          A01X+015372Y+051700X0180Y0200R180 S1      
327m0042            U403  -6          A01X+016493Y+051308X0110Y0360R270 S1      
327FAN_1_PWM_R2     R5577 -2          A01X+015372Y+052200X0180Y0200R180 S1      
327FAN_1_PWM_R2     VIA   -    M      A01X+015841Y+051623X0300Y         S1      
327FAN_1_PWM_R2     U403  -5          A01X+016493Y+051505X0110Y0360R270 S1      
317m0043            VIA   -    M      A01X+015372Y+052450X0200Y         S2      
017m0043            VIA   -    M      A06X+015372Y+052450X0260Y         S2      
017m0043                  -    MD0100PA00X+015372Y+052450                       
327m0043            R5576 -2          A01X+015372Y+052700X0180Y0200R180 S1      
327m0043            U403  -4          A01X+016493Y+051702X0110Y0360R270 S1      
327m0044            R5575 -2          A01X+015372Y+053200X0180Y0200R180 S1      
327m0044            VIA   -    M      A01X+015887Y+052551X0300Y         S1      
327m0044            U403  -3          A01X+016493Y+051898X0110Y0360R270 S1      
327m0045            R5574 -2          A01X+015372Y+053700X0180Y0200R180 S1      
327m0045            VIA   -    M      A01X+015879Y+053340X0300Y         S1      
327m0045            U403  -2          A01X+016493Y+052095X0110Y0360R270 S1      
327FAN_0_PWM_R2     R5573 -2          A01X+015365Y+054200X0180Y0200R180 S1      
327FAN_0_PWM_R2     VIA   -    M      A01X+015973Y+053952X0300Y         S1      
327FAN_0_PWM_R2     U403  -1          A01X+016493Y+052292X0110Y0360R270 S1      
327m0046            VIA   -    M      A01X+002210Y+052612X0300Y         S1      
327m0046            R5569 -2          A01X+002300Y+053092X0198Y0197R270 S1      
327m0046            U404  -19         A01X+002543Y+052142X0110Y0360R090 S1      
327m0047            VIA   -    M      A01X+001658Y+052622X0300Y         S1      
327m0047            R5568 -2          A01X+001900Y+053092X0198Y0197R270 S1      
327m0047            U404  -20         A01X+002543Y+051945X0110Y0360R090 S1      
317U404_ADD0        VIA   -    M      A01X+002758Y+052834X0200Y         S2      
017U404_ADD0        VIA   -    M      A06X+002758Y+052834X0260Y         S2      
017U404_ADD0              -    MD0100PA00X+002758Y+052834                       
327U404_ADD0        U404  -18         A01X+002858Y+052457X0110Y0360     S1      
327U404_ADD0        R5570 -2          A01X+003300Y+053092X0198Y0197R270 S1      
327U404_ADD0        R5565 -2   M      A01X+002700Y+053092X0198Y0197R270 S1      
317U404_ADD1        VIA   -    M      A01X+002045Y+051355X0200Y         S2      
017U404_ADD1        VIA   -    M      A06X+002045Y+051355X0260Y         S2      
017U404_ADD1              -    MD0100PA00X+002045Y+051355                       
327U404_ADD1        R5566 -2          A01X+001658Y+051100X0198Y0197     S1      
327U404_ADD1        U404  -23         A01X+002543Y+051355X0110Y0360R090 S1      
327U404_ADD1        R5571 -2   M      A01X+001658Y+051550X0198Y0197     S1      
327U404_ADD2        VIA   -    M      A01X+002132Y+050650X0300Y         S1      
327U404_ADD2        U404  -24         A01X+002543Y+051158X0110Y0360R090 S1      
327U404_ADD2        R5567 -2          A01X+001658Y+050200X0198Y0197     S1      
327U404_ADD2        R5572 -2   M      A01X+001658Y+050650X0198Y0197     S1      
327m0048            R5620 -2          A01X+006015Y+053600X0180Y0200R180 S1      
327m0048            VIA   -    M      A01X+006494Y+053450X0300Y         S1      
327m0048            U330  -9          A01X+007463Y+051165X0070Y0320R270 S1      
327FAN_7_PWM_R1     R5619 -2          A01X+006008Y+053100X0180Y0200R180 S1      
327FAN_7_PWM_R1     VIA   -    M      A01X+006471Y+052563X0300Y         S1      
327FAN_7_PWM_R1     U330  -10         A01X+007463Y+051008X0070Y0320R270 S1      
327m0049            R5618 -2          A01X+006008Y+052600X0180Y0200R180 S1      
327m0049            VIA   -    M      A01X+006482Y+052030X0300Y         S1      
327m0049            U330  -11         A01X+007463Y+050850X0070Y0320R270 S1      
327m0050            R5617 -2          A01X+006008Y+052100X0180Y0200R180 S1      
327m0050            VIA   -    M      A01X+006629Y+051522X0300Y         S1      
327m0050            U330  -12         A01X+007463Y+050692X0070Y0320R270 S1      
327m0051            R5616 -2          A01X+006008Y+051600X0180Y0200R180 S1      
327m0051            VIA   -    M      A01X+006480Y+051003X0300Y         S1      
327m0051            U330  -13         A01X+007463Y+050535X0070Y0320R270 S1      
327FAN_6_PWM_R1     R5615 -2          A01X+006008Y+051100X0180Y0200R180 S1      
327FAN_6_PWM_R1     VIA   -    M      A01X+006548Y+050481X0300Y         S1      
327FAN_6_PWM_R1     U330  -14         A01X+007463Y+050378X0070Y0320R270 S1      
327m0052            R5614 -2          A01X+006008Y+050600X0180Y0200R180 S1      
327m0052            VIA   -    M      A01X+006929Y+050079X0300Y         S1      
327m0052            U330  -15         A01X+007778Y+050063X0070Y0320     S1      
327FAN_5_PWM_R1     R5613 -2          A01X+006008Y+050050X0180Y0200R180 S1      
327FAN_5_PWM_R1     VIA   -    M      A01X+006470Y+049819X0300Y         S1      
327FAN_5_PWM_R1     U330  -16         A01X+007935Y+050063X0070Y0320     S1      
327m0053            R5612 -2          A01X+006008Y+049550X0180Y0200R180 S1      
327m0053            VIA   -    M      A01X+007046Y+049512X0300Y         S1      
327m0053            U330  -17         A01X+008092Y+050063X0070Y0320     S1      
327m0054            R5611 -2          A01X+006008Y+049050X0180Y0200R180 S1      
327m0054            VIA   -    M      A01X+006530Y+049050X0300Y         S1      
327m0054            U330  -18         A01X+008250Y+050063X0070Y0320     S1      
327m0055            R5610 -2          A01X+006008Y+048550X0180Y0200R180 S1      
327m0055            VIA   -    M      A01X+006893Y+048550X0300Y         S1      
327m0055            U330  -19         A01X+008408Y+050063X0070Y0320     S1      
327FAN_4_PWM_R1     R5609 -2          A01X+006015Y+048050X0180Y0200R180 S1      
327FAN_4_PWM_R1     VIA   -    M      A01X+006530Y+048050X0300Y         S1      
327FAN_4_PWM_R1     U330  -20         A01X+008565Y+050063X0070Y0320     S1      
317GND2             J85   -1   MD0670PA00X-002732Y+116600X0850Y    R180 S3      
317GND2             J83   -1   MD0670PA00X-005843Y+116600X0850Y    R180 S3      
317GND2             J81   -1   MD0670PA00X-002732Y+082400X0850Y         S3      
317GND2             J95   -1   MD0670PA00X-005843Y+082400X0850Y         S3      
327m0056            R5540 -2          A01X+006542Y+009800X0180Y0200     S1      
327m0056            R5349 -1          A01X+005950Y+010758X0180Y0200R090 S1      
317m0056            VIA   -    M      A01X+006535Y+010200X0200Y         S2      
017m0056            VIA   -    M      A06X+006535Y+010200X0260Y         S2      
017m0056                  -    MD0100PA00X+006535Y+010200                       
327m0056            U340  -D   M      A01X+006535Y+010600X0240Y0320R090 S1      
327m0057            R5534 -2   M      A01X+006442Y+116800X0180Y0200     S1      
327m0057            R5382 -1          A01X+005808Y+116850X0180Y0200     S1      
317m0057            VIA   -    M      A01X+006442Y+116550X0200Y         S2      
017m0057            VIA   -    M      A06X+006442Y+116550X0260Y         S2      
017m0057                  -    MD0100PA00X+006442Y+116550                       
327m0057            U367  -D          A01X+006485Y+116000X0240Y0320R090 S1      
327m0058            R5539 -2          A01X+006542Y+008100X0180Y0200     S1      
327m0058            R5358 -1          A01X+005950Y+009258X0180Y0200R090 S1      
317m0058            VIA   -    M      A01X+006402Y+009258X0200Y         S2      
017m0058            VIA   -    M      A06X+006402Y+009258X0260Y         S2      
017m0058                  -    MD0100PA00X+006402Y+009258                       
327m0058            U342  -D   M      A01X+006535Y+008900X0240Y0320R090 S1      
327m0059            R5536 -2          A01X+007142Y+082350X0180Y0200     S1      
327m0059            R5372 -1          A01X+005808Y+081600X0180Y0200     S1      
317m0059            VIA   -    M      A01X+006535Y+081865X0200Y         S2      
017m0059            VIA   -    M      A06X+006535Y+081865X0260Y         S2      
017m0059                  -    MD0100PA00X+006535Y+081865                       
327m0059            U364  -D   M      A01X+006535Y+081550X0240Y0320R090 S1      
327m0060            R5538 -2          A01X+006492Y+042700X0180Y0200     S1      
327m0060            R5366 -1          A01X+005950Y+043808X0180Y0200R090 S1      
317m0060            VIA   -    M      A01X+006700Y+043050X0200Y         S2      
017m0060            VIA   -    M      A06X+006700Y+043050X0260Y         S2      
017m0060                  -    MD0100PA00X+006700Y+043050                       
327m0060            U363  -D   M      A01X+006535Y+043500X0240Y0320R090 S1      
327m0061            R5533 -2          A01X+006442Y+118400X0180Y0200     S1      
327m0061            R5380 -1          A01X+005808Y+117850X0180Y0200     S1      
317m0061            VIA   -    M      A01X+006485Y+117900X0200Y         S2      
017m0061            VIA   -    M      A06X+006485Y+117900X0260Y         S2      
017m0061                  -    MD0100PA00X+006485Y+117900                       
327m0061            U366  -D   M      A01X+006485Y+117600X0240Y0320R090 S1      
327m0062            R5537 -2          A01X+006492Y+044350X0180Y0200     S1      
327m0062            R5364 -1          A01X+005950Y+045208X0180Y0200R090 S1      
317m0062            VIA   -    M      A01X+006535Y+044750X0200Y         S2      
017m0062            VIA   -    M      A06X+006535Y+044750X0260Y         S2      
017m0062                  -    MD0100PA00X+006535Y+044750                       
327m0062            U362  -D   M      A01X+006535Y+045150X0240Y0320R090 S1      
327m0063            R5535 -2          A01X+006492Y+080750X0180Y0200     S1      
327m0063            R5374 -1          A01X+005808Y+080500X0180Y0200     S1      
317m0063            VIA   -    M      A01X+006206Y+080108X0200Y         S2      
017m0063            VIA   -    M      A06X+006206Y+080108X0260Y         S2      
017m0063                  -    MD0100PA00X+006206Y+080108                       
327m0063            U365  -D   M      A01X+006535Y+079950X0240Y0320R090 S1      
327m0064            R5530 -2          A01X+012758Y+042900X0180Y0200R180 S1      
327m0064            R5410 -1          A01X+014500Y+043292X0180Y0200R270 S1      
317m0064            VIA   -    M      A01X+013915Y+042965X0200Y         S2      
017m0064            VIA   -    M      A06X+013915Y+042965X0260Y         S2      
017m0064                  -    MD0100PA00X+013915Y+042965                       
327m0064            U373  -D   M      A01X+013915Y+043250X0240Y0320R270 S1      
327m0065            R5526 -2          A01X+013908Y+117000X0180Y0200R180 S1      
327m0065            R5414 -1          A01X+014542Y+115600X0180Y0200R180 S1      
317m0065            VIA   -    M      A01X+013865Y+116550X0200Y         S2      
017m0065            VIA   -    M      A06X+013865Y+116550X0260Y         S2      
017m0065                  -    MD0100PA00X+013865Y+116550                       
327m0065            U369  -D   M      A01X+013865Y+116200X0240Y0320R270 S1      
327m0066            R5527 -2          A01X+012700Y+080458X0180Y0200R270 S1      
327m0066            R5412 -1          A01X+014492Y+079650X0180Y0200R180 S1      
317m0066            VIA   -    M      A01X+013908Y+080198X0200Y         S2      
017m0066            VIA   -    M      A06X+013908Y+080198X0260Y         S2      
017m0066                  -    MD0100PA00X+013908Y+080198                       
327m0066            U371  -D   M      A01X+013865Y+079850X0240Y0320R270 S1      
327m0067            R5529 -2          A01X+013958Y+042450X0180Y0200R180 S1      
327m0067            R5404 -1          A01X+014450Y+041992X0180Y0200R270 S1      
317m0067            VIA   -    M      A01X+013915Y+042019X0200Y         S2      
017m0067            VIA   -    M      A06X+013915Y+042019X0260Y         S2      
017m0067                  -    MD0100PA00X+013915Y+042019                       
327m0067            U372  -D   M      A01X+013915Y+041650X0240Y0320R270 S1      
327m0068            R5525 -2          A01X+013908Y+115400X0180Y0200R180 S1      
327m0068            R5400 -1          A01X+014542Y+114640X0180Y0200R180 S1      
317m0068            VIA   -    M      A01X+013865Y+114950X0200Y         S2      
017m0068            VIA   -    M      A06X+013865Y+114950X0260Y         S2      
017m0068                  -    MD0100PA00X+013865Y+114950                       
327m0068            U368  -D   M      A01X+013865Y+114600X0240Y0320R270 S1      
327m0069            R5528 -2          A01X+013908Y+079080X0180Y0200R180 S1      
327m0069            R5402 -1          A01X+014492Y+078650X0180Y0200R180 S1      
317m0069            VIA   -    M      A01X+013965Y+078590X0200Y         S2      
017m0069            VIA   -    M      A06X+013965Y+078590X0260Y         S2      
017m0069                  -    MD0100PA00X+013965Y+078590                       
327m0069            U370  -D   M      A01X+013965Y+078270X0240Y0320R270 S1      
327m0070            R5531 -2          A01X+013858Y+009700X0180Y0200R180 S1      
327m0070            R5408 -1          A01X+014450Y+008858X0180Y0200R090 S1      
317m0070            VIA   -    M      A01X+013865Y+009400X0200Y         S2      
017m0070            VIA   -    M      A06X+013865Y+009400X0260Y         S2      
017m0070                  -    MD0100PA00X+013865Y+009400                       
327m0070            U374  -D   M      A01X+013865Y+008900X0240Y0320R270 S1      
327m0071            R5532 -2          A01X+013858Y+008100X0180Y0200R180 S1      
327m0071            R5406 -1          A01X+014450Y+007458X0180Y0200R090 S1      
317m0071            VIA   -    M      A01X+014200Y+007458X0200Y         S2      
017m0071            VIA   -    M      A06X+014200Y+007458X0260Y         S2      
017m0071                  -    MD0100PA00X+014200Y+007458                       
327m0071            U375  -D   M      A01X+013865Y+007300X0240Y0320R270 S1      
327NC_U398_P1       VIA   -           A06X+007480Y+100346X0260Y         S2      
327NC_U398_P1       U398  -1          A06X+007001Y+100346X0240Y0240R270 S2      
327NC_U397_P1       VIA   -           A06X+001205Y+100340X0260Y         S2      
327NC_U397_P1       U397  -1          A06X+001205Y+099854X0240Y0240R090 S2      
327NC_U393_P1       VIA   -           A06X+007435Y+027668X0260Y         S2      
327NC_U393_P1       U393  -1          A06X+006951Y+027668X0240Y0240R270 S2      
327NC_U392_P1       VIA   -           A06X+000724Y+027104X0260Y         S2      
327NC_U392_P1       U392  -1          A06X+001205Y+027104X0240Y0240R090 S2      
327NC_U391_P1       U391  -1          A06X+013353Y+026977X0240Y0240R090 S2      
327NC_U394_P1       VIA   -           A06X+018360Y+100570X0260Y         S2      
327NC_U394_P1       U394  -1          A06X+017881Y+100346X0240Y0240R270 S2      
327NC_U396_P1       VIA   -           A06X+018360Y+027668X0260Y         S2      
327NC_U396_P1       U396  -1          A06X+017881Y+027668X0240Y0240R270 S2      
327NC_U395_P1       VIA   -           A06X+012870Y+099969X0260Y         S2      
327NC_U395_P1       U395  -1          A06X+013353Y+099969X0240Y0240R090 S2      
327NC_U402_P1       VIA   -           A01X+012030Y+114850X0300Y         S1      
327NC_U402_P1       U402  -1          A01X+011806Y+114374X0160Y0200     S1      
327NC_U401_P1       U401  -1          A01X+011706Y+078074X0160Y0200     S1      
327NC_U400_P1       VIA   -           A01X+012210Y+041810X0300Y         S1      
327NC_U400_P1       U400  -1          A01X+011756Y+041574X0160Y0200     S1      
327NC_U399_P1       U399  -1          A01X+011856Y+007874X0160Y0200     S1      
327NC_U66_P1        VIA   -           A01X+008140Y+009500X0300Y         S1      
327NC_U66_P1        U66   -1          A01X+008594Y+009726X0160Y0200R180 S1      
327NC_U64_P1        VIA   -           A01X+008065Y+045765X0300Y         S1      
327NC_U64_P1        U64   -1          A01X+008594Y+045526X0160Y0200R180 S1      
327NC_U62_P1        VIA   -           A01X+008050Y+082250X0300Y         S1      
327NC_U62_P1        U62   -1          A01X+008594Y+081826X0160Y0200R180 S1      
327NC_U60_P1        VIA   -           A01X+007999Y+118126X0300Y         S1      
327NC_U60_P1        U60   -1          A01X+008594Y+118126X0160Y0200R180 S1      
327NC_U317_CLKOUT   U317  -28         A01X+011613Y+050378X0070Y0320R090 S1      
327NC_U330_CLKOUT   U330  -28         A01X+009037Y+051322X0070Y0320R270 S1      
317U330_FAN FS_N    VIA   -    M      A01X+009628Y+051975X0200Y         S2      
017U330_FAN FS_N    VIA   -    M      A06X+009628Y+051975X0260Y         S2      
017U330_FAN FS_N          -    MD0100PA00X+009628Y+051975                       
327U330_FAN FS_N    R5680 -1          A01X+009892Y+052700X0180Y0200R180 S1      
327U330_FAN FS_N    U330  -27         A01X+009037Y+051165X0070Y0320R270 S1      
317m0072            VIA   -    MD0100PA00X+010208Y+053400X0200Y         S0      
327m0072            R5680 -2          A01X+010208Y+052700X0180Y0200R180 S1      
327m0072            R5682 -2   M      A01X+010208Y+053150X0198Y0197     S1      
327m0072            U330  -24         A01X+009037Y+050692X0070Y0320R270 S1      
317m0072            VIA   -    M      A01X+009518Y+049379X0200Y         S2      
017m0072            VIA   -    M      A06X+009518Y+049379X0260Y         S2      
017m0072                  -    MD0100PA00X+009518Y+049379                       
317m0073            VIA   -    M      A01X+010900Y+048500X0200Y         S2      
017m0073            VIA   -    M      A06X+010900Y+048500X0260Y         S2      
017m0073                  -    MD0100PA00X+010900Y+048500                       
327m0073            R5681 -2          A01X+010900Y+048158X0198Y0197R090 S1      
327m0073            R5679 -2          A01X+010900Y+048742X0180Y0200R090 S1      
317m0073            VIA   -    MD0100PA00X+010850Y+051200X0200Y         S0      
327m0073            U317  -24         A01X+011613Y+051008X0070Y0320R090 S1      
327U317_FAN FS_N    R5679 -1          A01X+010900Y+049058X0180Y0200R090 S1      
317U317_FAN FS_N    VIA   -    M      A01X+011207Y+049979X0200Y    R090 S2      
017U317_FAN FS_N    VIA   -    M      A06X+011207Y+049979X0260Y    R090 S2      
017U317_FAN FS_N          -    MD0100PA00X+011207Y+049979                       
327U317_FAN FS_N    U317  -27         A01X+011613Y+050535X0070Y0320R090 S1      
327NC_U390_E        U390  -10         A01X+015400Y+071244X0140Y0590R270 S1      
327NC_U390_F        U390  -12         A01X+015400Y+071756X0140Y0590R270 S1      
327NC_U389_E        U389  -10         A01X+015450Y+074344X0140Y0590R270 S1      
327NC_U389_F        U389  -12         A01X+015450Y+074856X0140Y0590R270 S1      
317m0074            J81   -3    D0670PA00X-002232Y+083718X0850Y         S3      
317m0074            J81   -2    D0670PA00X-003232Y+083718X0850Y         S3      
317m0075            J85   -3    D0670PA00X-002232Y+115282X0850Y    R180 S3      
317m0075            J85   -2    D0670PA00X-003232Y+115282X0850Y    R180 S3      
317m0076            J83   -2    D0670PA00X-005343Y+115282X0850Y    R180 S3      
317m0076            J83   -3    D0670PA00X-006343Y+115282X0850Y    R180 S3      
317m0077            J95   -2    D0670PA00X-005343Y+083718X0850Y         S3      
317m0077            J95   -3    D0670PA00X-006343Y+083718X0850Y         S3      
327PU_U7_PIN2       R5486 -2          A01X+003442Y+072750X0198Y0197R180 S1      
327PU_U7_PIN2       VIA   -    M      A01X+002900Y+072800X0300Y         S1      
327PU_U7_PIN2       U7    -1          A01X+002900Y+072258X0140Y0590R270 S1      
327m0078            R5320 -2   M      A01X+007060Y+113400X0280Y0320R090 S1      
327m0078            R5322 -1   M      A01X+007192Y+113850X0180Y0200R180 S1      
327m0078            C2058 -1          A01X+007197Y+114265X0198Y0197     S1      
317m0078            VIA   -    M      A01X+006869Y+113999X0200Y         S2      
017m0078            VIA   -    M      A06X+006869Y+113999X0260Y         S2      
017m0078                  -    MD0100PA00X+006869Y+113999                       
327m0078            D142  -1          A01X+006484Y+113615X0320Y0340     S1      
327m0079            R5317 -2   M      A01X+007110Y+082850X0280Y0320R090 S1      
327m0079            R5319 -1   M      A01X+007008Y+083400X0180Y0200     S1      
327m0079            C2047 -1          A01X+007392Y+083400X0198Y0197     S1      
317m0079            VIA   -    M      A01X+006799Y+082776X0200Y         S2      
017m0079            VIA   -    M      A06X+006799Y+082776X0260Y         S2      
017m0079                  -    MD0100PA00X+006799Y+082776                       
327m0079            D140  -1          A01X+006484Y+082726X0320Y0340     S1      
327m0080            VIA   -    M      A01X+006731Y+011425X0300Y         S1      
327m0080            D114  -1          A01X+006534Y+012034X0320Y0340     S1      
327m0080            R5309 -2   M      A01X+007094Y+011950X0280Y0320R090 S1      
327m0080            C2017 -1          A01X+007550Y+012442X0198Y0197R090 S1      
327m0080            R5311 -1   M      A01X+007150Y+012442X0180Y0200R270 S1      
327FAN_2_ON         PU5   -26         A06X+016306Y+030494X0070Y0360R180 S2      
317FAN_2_ON         VIA   -    MD0100PA00X+016278Y+030146X0200Y         S0      
327FAN_2_ON         R5421 -1          A01X+015593Y+027773X0198Y0197R180 S1      
317FAN_2_ON         VIA   -    M      A01X+016078Y+027569X0300Y         S1      
017FAN_2_ON         VIA   -    M      A06X+016078Y+027569X0200Y         S1      
017FAN_2_ON               -    MD0100PA00X+016078Y+027569                       
327m0081            R5420 -1          A01X+016628Y+028373X0198Y0197     S1      
317m0081            VIA   -    M      A01X+016786Y+027931X0200Y         S2      
017m0081            VIA   -    M      A06X+016786Y+027931X0260Y         S2      
017m0081                  -    MD0100PA00X+016786Y+027931                       
327m0081            U381  -1          A06X+016115Y+028329X0130Y0460R090 S2      
327FAN_2_PRESENT    R5656 -1   M      A01X+014850Y+038742X0198Y0197R090 S1      
327FAN_2_PRESENT    U407  -G          A01X+015385Y+039156X0240Y0320R270 S1      
317FAN_2_PRESENT    VIA   -    M      A01X+011000Y+039250X0300Y         S1      
017FAN_2_PRESENT    VIA   -    M      A06X+011000Y+039250X0200Y         S1      
017FAN_2_PRESENT          -    MD0100PA00X+011000Y+039250                       
327FAN_2_PRESENT    R5420 -2          A01X+016943Y+028373X0198Y0197     S1      
317FAN_2_PRESENT    VIA   -    MD0100PA00X+016936Y+028623X0200Y         S0      
327FAN_2_PRESENT    U396  -4          A06X+017290Y+028377X0240Y0240R270 S2      
327FAN_1_TEMP       PC2119-1          A06X+016600Y+098361X0198Y0197R270 S2      
327FAN_1_TEMP       PR32  -1   M      A06X+016192Y+098361X0198Y0197R270 S2      
317FAN_1_TEMP       VIA   -    M      A01X+016073Y+097797X0300Y    R180 S1      
017FAN_1_TEMP       VIA   -    M      A06X+016073Y+097797X0200Y    R180 S1      
017FAN_1_TEMP             -    MD0100PA00X+016073Y+097797                       
327FAN_1_TEMP       PU4   -29         A06X+015401Y+097144X0070Y0360     S2      
327SMB_FAN5_SCL_R   VIA   -    M      A01X+005000Y+042800X0300Y         S1      
317SMB_FAN5_SCL_R   J6    -6    D0380PA00X+003425Y+042799X0540Y    R270 S3      
327SMB_FAN5_SCL_R   R5203 -2          A01X+005492Y+042473X0198Y0197R180 S1      
327FAN_1_IMON       PR34  -2          A06X+013050Y+098361X0198Y0197R090 S2      
327FAN_1_IMON       VIA   -    M      A06X+013398Y+097909X0260Y    R180 S2      
327FAN_1_IMON       PU4   -20         A06X+013983Y+097144X0070Y0360     S2      
317FAN_1_SS         VIA   -    M      A01X+013860Y+097765X0300Y    R180 S1      
017FAN_1_SS         VIA   -    M      A06X+013860Y+097765X0200Y    R180 S1      
017FAN_1_SS               -    MD0100PA00X+013860Y+097765                       
327FAN_1_SS         PU4   -21         A06X+014141Y+097144X0070Y0360     S2      
327FAN_1_SS         PC27  -1          A06X+013450Y+098361X0198Y0197R270 S2      
327m0082            R5308 -2   M      A01X+007210Y+006300X0280Y0320R090 S1      
327m0082            C2016 -1          A01X+007650Y+006742X0198Y0197R090 S1      
327m0082            R5310 -1   M      A01X+007250Y+006742X0180Y0200R270 S1      
327m0082            D113  -1          A01X+006484Y+006384X0320Y0340     S1      
317m0082            VIA   -    M      A01X+006842Y+006384X0200Y         S2      
017m0082            VIA   -    M      A06X+006842Y+006384X0260Y         S2      
017m0082                  -    MD0100PA00X+006842Y+006384                       
327FAN_1_P3V_R      PC25  -1          A06X+015350Y+098361X0198Y0197R270 S2      
317FAN_1_P3V_R      VIA   -    M      A01X+015282Y+097857X0300Y    R180 S1      
017FAN_1_P3V_R      VIA   -    M      A06X+015282Y+097857X0200Y    R180 S1      
017FAN_1_P3V_R            -    MD0100PA00X+015282Y+097857                       
327FAN_1_P3V_R      PU4   -27         A06X+015086Y+097144X0070Y0360     S2      
327FAN_1_P3V_R      PR29  -1          A01X+014908Y+098500X0198Y0197R180 S1      
327FAN_1_P3V_R      PR27  -2   M      A01X+014908Y+098900X0198Y0197     S1      
327FAN_1_TIMER      PU4   -23         A06X+014456Y+097144X0070Y0360     S2      
327FAN_1_TIMER      PC28  -1          A06X+013850Y+098361X0198Y0197R270 S2      
327FAN_1_CLREF      PU4   -24         A06X+014613Y+097144X0070Y0360     S2      
327FAN_1_CLREF      VIA   -    M      A06X+014650Y+097880X0260Y         S2      
327FAN_1_CLREF      PC3119-2   M      A06X+014650Y+098361X0198Y0197R090 S2      
327FAN_1_CLREF      PR33  -1          A06X+014250Y+098361X0198Y0197R270 S2      
327m0083            R5312 -2          A01X+007260Y+041500X0280Y0320R090 S1      
327m0083            R5314 -1   M      A01X+007192Y+040600X0180Y0200R180 S1      
327m0083            C2034 -1   M      A01X+007192Y+041000X0198Y0197     S1      
317m0083            VIA   -    M      A01X+006590Y+041300X0200Y         S2      
017m0083            VIA   -    M      A06X+006590Y+041300X0260Y         S2      
017m0083                  -    MD0100PA00X+006590Y+041300                       
327m0083            D134  -1          A01X+006484Y+040888X0320Y0340     S1      
327FAN_1_FAULT      PR28  -2          A01X+014200Y+098442X0180Y0200R090 S1      
327FAN_1_FAULT      VIA   -    M      A01X+013650Y+098647X0300Y         S1      
327FAN_1_FAULT      PU4   -22         A06X+014298Y+097144X0070Y0360     S2      
317FAN_1_FAULT      VIA   -    MD0100PA00X+014200Y+097750X0200Y         S0      
327SMB_FAN4_SDA_R   R5132 -1          A01X+005492Y+008419X0198Y0197     S1      
317SMB_FAN4_SDA_R   J5    -7    D0380PA00X+002638Y+007248X0540Y    R270 S3      
327SMB_FAN4_SDA_R   VIA   -    M      A01X+004998Y+008118X0300Y         S1      
317m0084            VIA   -    M      A01X+012607Y+049393X0200Y         S2      
017m0084            VIA   -    M      A06X+012607Y+049393X0260Y         S2      
017m0084                  -    MD0100PA00X+012607Y+049393                       
327m0084            R4781 -2          A01X+013000Y+048158X0198Y0197R090 S1      
327m0084            R4778 -2   M      A01X+013000Y+049058X0198Y0197R090 S1      
327m0084            U317  -4          A01X+012400Y+050063X0070Y0320R180 S1      
327FAN_1_CS         PR30  -1          A06X+012650Y+098361X0198Y0197R270 S2      
317FAN_1_CS         VIA   -    M      A01X+012911Y+097877X0300Y         S1      
017FAN_1_CS         VIA   -    M      A06X+012911Y+097877X0200Y         S1      
017FAN_1_CS               -    MD0100PA00X+012911Y+097877                       
327FAN_1_CS         PU4   -19         A06X+013826Y+097144X0276Y0354     S2      
327FAN_1_MODE       VIA   -    M      A01X+015450Y+097110X0300Y         S1      
327FAN_1_MODE       PR29  -2          A01X+014592Y+098500X0198Y0197R180 S1      
327FAN_1_MODE       PR31  -1   M      A01X+014442Y+098050X0198Y0197     S1      
317FAN_1_MODE       VIA   -    MD0100PA00X+015900Y+097250X0200Y    R180 S0      
327FAN_1_MODE       PU4   -30         A06X+015558Y+097144X0276Y0354     S2      
327FAN_1_FAULT_R    PR28  -1          A01X+014200Y+098758X0180Y0200R090 S1      
327FAN_1_FAULT_R    PR27  -1          A01X+014592Y+098900X0198Y0197     S1      
317SMB_FAN7_SDA_R   VIA   -    MD0100PA00X+004050Y+116400X0200Y         S0      
327SMB_FAN7_SDA_R   VIA   -    M      A01X+004700Y+116650X0300Y         S1      
317SMB_FAN7_SDA_R   J8    -7    D0380PA00X+002638Y+116264X0540Y    R270 S3      
327SMB_FAN7_SDA_R   R5245 -1          A01X+005492Y+116400X0198Y0197     S1      
327SMB_FAN0_SCL_R   VIA   -    M      A01X+015529Y+117598X0300Y         S1      
317SMB_FAN0_SCL_R   J1    -6    D0380PA00X+016929Y+117839X0540Y    R090 S3      
327SMB_FAN0_SCL_R   R5187 -2          A01X+014858Y+117400X0198Y0197     S1      
327FAN_1_P5V        PC26  -1          A06X+015792Y+098361X0198Y0197R270 S2      
327FAN_1_P5V        VIA   -    M      A06X+015700Y+097900X0260Y    R180 S2      
327FAN_1_P5V        PU4   -28         A06X+015243Y+097144X0070Y0360     S2      
317m0085            VIA   -    M      A01X+007929Y+052351X0200Y         S2      
017m0085            VIA   -    M      A06X+007929Y+052351X0260Y         S2      
017m0085                  -    MD0100PA00X+007929Y+052351                       
327m0085            R4848 -2          A01X+007650Y+052592X0198Y0197R270 S1      
327m0085            U330  -4          A01X+008250Y+051637X0070Y0320     S1      
327m0085            R4850 -2          A01X+007650Y+053392X0198Y0197R270 S1      
327FAN_1_TACH_IL    R5306 -2          A01X+012842Y+082461X0180Y0200     S1      
327FAN_1_TACH_IL    R5428 -1          A06X+015942Y+052550X0180Y0200     S2      
327FAN_1_TACH_IL    R5575 -1          A01X+015058Y+053200X0180Y0200R180 S1      
327FAN_1_TACH_IL    R5599 -1   M      A01X+015058Y+053200X0180Y0200     S1      
317FAN_1_TACH_IL    VIA   -    M      A01X+015058Y+053450X0200Y         S2      
017FAN_1_TACH_IL    VIA   -    M      A06X+015058Y+053450X0260Y         S2      
017FAN_1_TACH_IL          -    MD0100PA00X+015058Y+053450                       
317FAN_1_TACH_IL    VIA   -    MD0100PA00X+013325Y+081130X0200Y         S0      
317m0086            VIA   -    M      A01X+008472Y+053220X0200Y         S2      
017m0086            VIA   -    M      A06X+008472Y+053220X0260Y         S2      
017m0086                  -    MD0100PA00X+008472Y+053220                       
327m0086            R4851 -2          A01X+008200Y+053392X0198Y0197R270 S1      
327m0086            R4849 -2   M      A01X+008200Y+052592X0198Y0197R270 S1      
327m0086            U330  -3          A01X+008408Y+051637X0070Y0320     S1      
327SMB_FAN5_R_SCL   R4877 -1   M      A01X+011400Y+062842X0198Y0197R090 S1      
327SMB_FAN5_R_SCL   R5270 -1          A01X+011400Y+063992X0198Y0197R090 S1      
327SMB_FAN5_R_SCL   VIA   -    M      A01X+010700Y+062100X0300Y         S1      
327SMB_FAN5_R_SCL   U321  -16         A01X+010390Y+061000X0140Y0590     S1      
327FAN_2_TACH_IL    R5330 -2          A01X+012842Y+046550X0180Y0200     S1      
327FAN_2_TACH_IL    R5430 -1          A06X+015942Y+051200X0180Y0200     S2      
327FAN_2_TACH_IL    R5580 -1          A01X+015058Y+050700X0180Y0200R180 S1      
327FAN_2_TACH_IL    R5604 -1   M      A01X+015058Y+050700X0180Y0200     S1      
317FAN_2_TACH_IL    VIA   -    MD0100PA00X+015058Y+050950X0200Y         S0      
317FAN_2_TACH_IL    VIA   -    M      A01X+012900Y+046800X0200Y         S2      
017FAN_2_TACH_IL    VIA   -    M      A06X+012900Y+046800X0260Y         S2      
017FAN_2_TACH_IL          -    MD0100PA00X+012900Y+046800                       
327SMB_FAN5_SDA_R   VIA   -    M      A01X+004650Y+043212X0300Y         S1      
317SMB_FAN5_SDA_R   J6    -7    D0380PA00X+002638Y+043587X0540Y    R270 S3      
327SMB_FAN5_SDA_R   R5205 -1          A01X+005492Y+042923X0198Y0197     S1      
327FAN_3_TACH_IL    R5326 -2          A01X+012792Y+011400X0180Y0200     S1      
327FAN_3_TACH_IL    R5432 -1          A06X+015942Y+050750X0180Y0200     S2      
327FAN_3_TACH_IL    R5581 -1          A01X+015058Y+050200X0180Y0200R180 S1      
327FAN_3_TACH_IL    R5605 -1   M      A01X+015058Y+050200X0180Y0200     S1      
317FAN_3_TACH_IL    VIA   -    M      A01X+015058Y+050450X0200Y         S2      
017FAN_3_TACH_IL    VIA   -    M      A06X+015058Y+050450X0260Y         S2      
017FAN_3_TACH_IL          -    MD0100PA00X+015058Y+050450                       
317FAN_3_TACH_IL    VIA   -    M      A01X+012350Y+011550X0200Y         S2      
017FAN_3_TACH_IL    VIA   -    M      A06X+012350Y+011550X0260Y         S2      
017FAN_3_TACH_IL          -    MD0100PA00X+012350Y+011550                       
327SMB_FAN4_R_SDA   R5269 -1          A01X+013850Y+063992X0198Y0197R090 S1      
327SMB_FAN4_R_SDA   R4876 -1   M      A01X+013500Y+062842X0198Y0197R090 S1      
327SMB_FAN4_R_SDA   VIA   -    M      A01X+013188Y+062338X0300Y         S1      
327SMB_FAN4_R_SDA   U321  -13         A01X+011158Y+061000X0140Y0590     S1      
327m0087            R5313 -2   M      A01X+007200Y+046890X0280Y0320     S1      
327m0087            D136  -1          A01X+006484Y+046388X0320Y0340     S1      
317m0087            VIA   -    M      A01X+006800Y+046388X0200Y         S2      
017m0087            VIA   -    M      A06X+006800Y+046388X0260Y         S2      
017m0087                  -    MD0100PA00X+006800Y+046388                       
327m0087            R5315 -1          A01X+006158Y+047500X0180Y0200     S1      
327m0087            C2035 -1   M      A01X+006892Y+047500X0198Y0197     S1      
327FAN_4_TACH_IL    R5310 -2          A01X+007250Y+007058X0180Y0200R270 S1      
317FAN_4_TACH_IL    VIA   -    M      A01X+006850Y+007000X0200Y    R180 S2      
017FAN_4_TACH_IL    VIA   -    M      A06X+006850Y+007000X0260Y    R180 S2      
017FAN_4_TACH_IL          -    MD0100PA00X+006850Y+007000                       
327FAN_4_TACH_IL    R5434 -1          A06X+006792Y+049700X0180Y0200     S2      
327FAN_4_TACH_IL    R5586 -1          A01X+005692Y+048550X0180Y0200     S1      
327FAN_4_TACH_IL    R5610 -1   M      A01X+005692Y+048550X0180Y0200R180 S1      
317FAN_4_TACH_IL    VIA   -    MD0100PA00X+005692Y+048800X0200Y         S0      
317SMB_FAN3_SDA     VIA   -    MD0100PA00X+013349Y+056049X0200Y    R090 S0      
327SMB_FAN3_SDA     R4788 -2          A01X+013150Y+056492X0198Y0197R270 S1      
317SMB_FAN3_SDA     VIA   -    MD0100PA00X+014200Y+009884X0200Y         S0      
327SMB_FAN3_SDA     R5244 -2          A01X+014542Y+009884X0198Y0197R180 S1      
317SMB_FAN3_SDA     VIA   -    M      A01X+013745Y+011334X0200Y         S2      
017SMB_FAN3_SDA     VIA   -    M      A06X+013745Y+011334X0260Y         S2      
017SMB_FAN3_SDA           -    MD0100PA00X+013745Y+011334                       
327m0088            VIA   -    M      A01X+009348Y+049057X0300Y         S1      
327m0088            R5461 -2          A01X+009892Y+048342X0198Y0197R180 S1      
327m0088            U330  -23         A01X+009037Y+050535X0070Y0320R270 S1      
317m0089            J8    -4    D0380PA00X+003425Y+114689X0540Y    R270 S3      
327m0089            R5502 -1          A01X+007208Y+068500X0198Y0197R180 S1      
317m0089            VIA   -    M      A01X+005948Y+068898X0200Y         S2      
017m0089            VIA   -    M      A06X+005948Y+068898X0260Y         S2      
017m0089                  -    MD0100PA00X+005948Y+068898                       
327FAN_5_TACH_IL    R5314 -2          A01X+007508Y+040600X0180Y0200R180 S1      
327FAN_5_TACH_IL    R5436 -1          A06X+006792Y+050150X0180Y0200     S2      
327FAN_5_TACH_IL    R5587 -1          A01X+005692Y+049050X0180Y0200     S1      
327FAN_5_TACH_IL    R5611 -1   M      A01X+005692Y+049050X0180Y0200R180 S1      
317FAN_5_TACH_IL    VIA   -    MD0100PA00X+005692Y+049300X0200Y         S0      
317FAN_5_TACH_IL    VIA   -    M      A01X+007850Y+040600X0200Y    R180 S2      
017FAN_5_TACH_IL    VIA   -    M      A06X+007850Y+040600X0260Y    R180 S2      
017FAN_5_TACH_IL          -    MD0100PA00X+007850Y+040600                       
327SMB_FAN3_R_SCL   R5282 -1          A01X+013550Y+055808X0198Y0197R270 S1      
327SMB_FAN3_R_SCL   R4792 -1   M      A01X+013550Y+056808X0198Y0197R270 S1      
317SMB_FAN3_R_SCL   VIA   -    M      A01X+012000Y+058150X0200Y         S2      
017SMB_FAN3_R_SCL   VIA   -    M      A06X+012000Y+058150X0260Y         S2      
017SMB_FAN3_R_SCL         -    MD0100PA00X+012000Y+058150                       
327SMB_FAN3_R_SCL   U321  -11         A01X+010902Y+058700X0140Y0590     S1      
327m0090            VIA   -    M      A01X+009365Y+048262X0300Y         S1      
327m0090            R5460 -2          A01X+009892Y+047850X0198Y0197R180 S1      
327m0090            U330  -22         A01X+009037Y+050378X0070Y0320R270 S1      
327FAN_6_TACH_IL    R5318 -2          A01X+007200Y+076992X0180Y0200R090 S1      
327FAN_6_TACH_IL    R5438 -1          A06X+006792Y+051500X0180Y0200     S2      
327FAN_6_TACH_IL    R5592 -1          A01X+005692Y+051600X0180Y0200     S1      
327FAN_6_TACH_IL    R5616 -1   M      A01X+005692Y+051600X0180Y0200R180 S1      
317FAN_6_TACH_IL    VIA   -    MD0100PA00X+006900Y+077150X0200Y         S0      
317FAN_6_TACH_IL    VIA   -    M      A01X+005692Y+051850X0200Y         S2      
017FAN_6_TACH_IL    VIA   -    M      A06X+005692Y+051850X0260Y         S2      
017FAN_6_TACH_IL          -    MD0100PA00X+005692Y+051850                       
327SMB_FAN0_SCL     R4789 -2          A01X+009300Y+056492X0198Y0197R270 S1      
317SMB_FAN0_SCL     VIA   -    M      A01X+009068Y+056177X0200Y    R090 S2      
017SMB_FAN0_SCL     VIA   -    M      A06X+009068Y+056177X0260Y    R090 S2      
017SMB_FAN0_SCL           -    MD0100PA00X+009068Y+056177                       
327SMB_FAN0_SCL     R5187 -1          A01X+014542Y+117400X0198Y0197     S1      
317SMB_FAN0_SCL     VIA   -    MD0100PA00X+014250Y+117600X0200Y         S0      
327m0091            VIA   -    M      A01X+010732Y+051964X0300Y         S1      
327m0091            R5459 -2          A01X+010600Y+053142X0198Y0197R270 S1      
327m0091            U317  -23         A01X+011613Y+051165X0070Y0320R090 S1      
327SMB_FAN6_R_SDA   R4880 -1   M      A01X+010500Y+062842X0198Y0197R090 S1      
327SMB_FAN6_R_SDA   R5273 -1          A01X+010700Y+063992X0198Y0197R090 S1      
317SMB_FAN6_R_SDA   VIA   -    M      A01X+010304Y+062446X0200Y         S2      
017SMB_FAN6_R_SDA   VIA   -    M      A06X+010304Y+062446X0260Y         S2      
017SMB_FAN6_R_SDA         -    MD0100PA00X+010304Y+062446                       
327SMB_FAN6_R_SDA   U321  -17         A01X+010134Y+061000X0140Y0590     S1      
327FAN_7_TACH_IL    R5322 -2          A01X+007508Y+113850X0180Y0200R180 S1      
327FAN_7_TACH_IL    R5440 -1          A06X+006792Y+051950X0180Y0200     S2      
327FAN_7_TACH_IL    R5593 -1          A01X+005692Y+052100X0180Y0200     S1      
327FAN_7_TACH_IL    R5617 -1   M      A01X+005692Y+052100X0180Y0200R180 S1      
317FAN_7_TACH_IL    VIA   -    M      A01X+005692Y+052350X0200Y         S2      
017FAN_7_TACH_IL    VIA   -    M      A06X+005692Y+052350X0260Y         S2      
017FAN_7_TACH_IL          -    MD0100PA00X+005692Y+052350                       
317FAN_7_TACH_IL    VIA   -    MD0100PA00X+007752Y+113850X0200Y    R180 S0      
327SMB_FAN1_SDA     R4786 -2          A01X+010100Y+056492X0198Y0197R270 S1      
327SMB_FAN1_SDA     R5204 -2          A01X+014542Y+080611X0198Y0197R180 S1      
317SMB_FAN1_SDA     VIA   -    MD0100PA00X+014109Y+080471X0200Y         S0      
317SMB_FAN1_SDA     VIA   -    M      A01X+009700Y+056915X0200Y    R090 S2      
017SMB_FAN1_SDA     VIA   -    M      A06X+009700Y+056915X0260Y    R090 S2      
017SMB_FAN1_SDA           -    MD0100PA00X+009700Y+056915                       
327m0092            VIA   -    M      A01X+011000Y+052649X0300Y         S1      
327m0092            R5458 -2          A01X+011000Y+053142X0198Y0197R270 S1      
327m0092            U317  -22         A01X+011613Y+051322X0070Y0320R090 S1      
327SMB_FAN6_R_SCL   R4879 -1   M      A01X+009850Y+062842X0198Y0197R090 S1      
327SMB_FAN6_R_SCL   R5272 -1          A01X+009850Y+063992X0198Y0197R090 S1      
317SMB_FAN6_R_SCL   VIA   -    M      A01X+009878Y+061700X0200Y         S2      
017SMB_FAN6_R_SCL   VIA   -    M      A06X+009878Y+061700X0260Y         S2      
017SMB_FAN6_R_SCL         -    MD0100PA00X+009878Y+061700                       
327SMB_FAN6_R_SCL   U321  -18         A01X+009878Y+061000X0140Y0590     S1      
327SMB_FAN6_SDA_R   VIA   -    M      A01X+004690Y+079513X0300Y         S1      
317SMB_FAN6_SDA_R   J7    -7    D0380PA00X+002638Y+079925X0540Y    R270 S3      
327SMB_FAN6_SDA_R   R5225 -1          A01X+005492Y+079261X0198Y0197     S1      
327SMB_FAN2_SDA     R5224 -2          A01X+014542Y+044273X0198Y0197R180 S1      
317SMB_FAN2_SDA     VIA   -    MD0100PA00X+009150Y+043400X0200Y         S0      
317SMB_FAN2_SDA     VIA   -    M      A01X+012150Y+055750X0200Y         S2      
017SMB_FAN2_SDA     VIA   -    M      A06X+012150Y+055750X0260Y         S2      
017SMB_FAN2_SDA           -    MD0100PA00X+012150Y+055750                       
327SMB_FAN2_SDA     R4787 -2          A01X+011700Y+056492X0198Y0197R270 S1      
327SMB_FAN4_R_SCL   R5288 -1          A01X+012650Y+063992X0198Y0197R090 S1      
327SMB_FAN4_R_SCL   R4874 -1   M      A01X+013100Y+062842X0198Y0197R090 S1      
327SMB_FAN4_R_SCL   VIA   -    M      A01X+012432Y+062175X0300Y         S1      
327SMB_FAN4_R_SCL   U321  -14         A01X+010902Y+061000X0140Y0590     S1      
327SMB_FAN3_R_SDA   R5283 -1          A01X+013150Y+055808X0198Y0197R270 S1      
327SMB_FAN3_R_SDA   R4788 -1   M      A01X+013150Y+056808X0198Y0197R270 S1      
327SMB_FAN3_R_SDA   VIA   -    M      A01X+012360Y+057597X0300Y         S1      
327SMB_FAN3_R_SDA   U321  -10         A01X+010646Y+058700X0140Y0590     S1      
327SMB_FAN7_R_SDA   R4884 -1          A01X+009100Y+062842X0198Y0197R090 S1      
327SMB_FAN7_R_SDA   R5275 -1          A01X+009250Y+063992X0198Y0197R090 S1      
327SMB_FAN7_R_SDA   VIA   -    M      A01X+009573Y+062211X0300Y         S1      
327SMB_FAN7_R_SDA   U321  -19         A01X+009622Y+061000X0140Y0590     S1      
327FAN_6_CS         PR66  -1          A06X+000650Y+098042X0198Y0197R270 S2      
327FAN_6_CS         PU8   -19         A06X+001457Y+096829X0276Y0354     S2      
327FAN_6_CS         VIA   -    M      A06X+000861Y+096732X0260Y         S2      
327SMB_FAN1_SCL     R4790 -2          A01X+010750Y+056492X0198Y0197R270 S1      
317SMB_FAN1_SCL     VIA   -    M      A01X+010698Y+056192X0200Y    R090 S2      
017SMB_FAN1_SCL     VIA   -    M      A06X+010698Y+056192X0260Y    R090 S2      
017SMB_FAN1_SCL           -    MD0100PA00X+010698Y+056192                       
327SMB_FAN1_SCL     R5202 -1          A01X+014542Y+081061X0198Y0197     S1      
317SMB_FAN1_SCL     VIA   -    MD0100PA00X+013843Y+080690X0200Y         S0      
327SMB_FAN5_R_SDA   R4878 -1   M      A01X+012100Y+062842X0198Y0197R090 S1      
327SMB_FAN5_R_SDA   R5271 -1          A01X+012100Y+063992X0198Y0197R090 S1      
327SMB_FAN5_R_SDA   VIA   -    M      A01X+011550Y+062200X0300Y         S1      
327SMB_FAN5_R_SDA   U321  -15         A01X+010646Y+061000X0140Y0590     S1      
327FAN_6_P5V        PC51  -1          A06X+003450Y+098042X0198Y0197R270 S2      
327FAN_6_P5V        VIA   -    M      A06X+003179Y+097550X0260Y    R180 S2      
327FAN_6_P5V        PU8   -28         A06X+002874Y+096829X0070Y0360     S2      
327SMB_FAN1_R_SDA   R5279 -1          A01X+010100Y+055908X0198Y0197R270 S1      
317SMB_FAN1_R_SDA   VIA   -    M      A01X+010050Y+056192X0200Y         S2      
017SMB_FAN1_R_SDA   VIA   -    M      A06X+010050Y+056192X0260Y         S2      
017SMB_FAN1_R_SDA         -    MD0100PA00X+010050Y+056192                       
327SMB_FAN1_R_SDA   U321  -6          A01X+009622Y+058700X0140Y0590     S1      
327SMB_FAN1_R_SDA   R4786 -1   M      A01X+010100Y+056808X0198Y0197R270 S1      
327FAN_6_CLREF      VIA   -    M      A06X+002263Y+097571X0260Y         S2      
327FAN_6_CLREF      PC3124-2          A06X+002292Y+098450X0198Y0197     S2      
327FAN_6_CLREF      PR69  -1   M      A06X+002292Y+098050X0198Y0197R180 S2      
327FAN_6_CLREF      PU8   -24         A06X+002244Y+096829X0070Y0360     S2      
327SMB_FAN3_SCL     R4792 -2          A01X+013550Y+056492X0198Y0197R270 S1      
317SMB_FAN3_SCL     VIA   -    MD0100PA00X+013550Y+056250X0200Y    R090 S0      
327SMB_FAN3_SCL     R5242 -1          A01X+014542Y+010334X0198Y0197     S1      
317SMB_FAN3_SCL     VIA   -    M      A01X+014250Y+010334X0200Y         S2      
017SMB_FAN3_SCL     VIA   -    M      A06X+014250Y+010334X0260Y         S2      
017SMB_FAN3_SCL           -    MD0100PA00X+014250Y+010334                       
327FAN_6_P3V_R      PR65  -1          A01X+002308Y+097450X0198Y0197R180 S1      
327FAN_6_P3V_R      PC50  -1          A06X+003050Y+098042X0198Y0197R270 S2      
317FAN_6_P3V_R      VIA   -    M      A01X+002789Y+097213X0300Y         S1      
017FAN_6_P3V_R      VIA   -    M      A06X+002789Y+097213X0200Y         S1      
017FAN_6_P3V_R            -    MD0100PA00X+002789Y+097213                       
317FAN_6_P3V_R      VIA   -    MD0100PA00X+002879Y+097692X0200Y    R180 S0      
327FAN_6_P3V_R      PU8   -27         A06X+002717Y+096829X0070Y0360     S2      
327FAN_6_P3V_R      PR63  -2          A01X+002508Y+098550X0198Y0197     S1      
327SMB_FAN2_SCL     R4791 -2          A01X+012450Y+056492X0198Y0197R270 S1      
317SMB_FAN2_SCL     VIA   -    MD0100PA00X+012500Y+056250X0200Y    R090 S0      
327SMB_FAN2_SCL     R5222 -1          A01X+014542Y+044723X0198Y0197     S1      
317SMB_FAN2_SCL     VIA   -    M      A01X+009159Y+043900X0200Y         S2      
017SMB_FAN2_SCL     VIA   -    M      A06X+009159Y+043900X0260Y         S2      
017SMB_FAN2_SCL           -    MD0100PA00X+009159Y+043900                       
317FAN_6_TEMP       VIA   -    M      A01X+003850Y+097720X0300Y    R180 S1      
017FAN_6_TEMP       VIA   -    M      A06X+003850Y+097720X0200Y    R180 S1      
017FAN_6_TEMP             -    MD0100PA00X+003850Y+097720                       
327FAN_6_TEMP       PU8   -29         A06X+003032Y+096829X0070Y0360     S2      
327FAN_6_TEMP       PC2124-1          A06X+004250Y+098042X0198Y0197R270 S2      
327FAN_6_TEMP       PR68  -1   M      A06X+003850Y+098042X0198Y0197R270 S2      
327FAN_7_PWM_BUF    R5518 -2          A01X+011250Y+113158X0198Y0197R090 S1      
317FAN_7_PWM_BUF    VIA   -    M      A01X+010950Y+113950X0200Y         S2      
017FAN_7_PWM_BUF    VIA   -    M      A06X+010950Y+113950X0260Y         S2      
017FAN_7_PWM_BUF          -    MD0100PA00X+010950Y+113950                       
327FAN_7_PWM_BUF    U329  -3          A01X+010524Y+113950X0280Y0360R090 S1      
327FAN_7_PWM_BUF    U402  -4   M      A01X+011294Y+113626X0160Y0200     S1      
327SMB_FAN0_SDA     R4785 -2          A01X+008500Y+056492X0198Y0197R270 S1      
317SMB_FAN0_SDA     VIA   -    MD0100PA00X+008500Y+056215X0200Y    R090 S0      
317SMB_FAN0_SDA     VIA   -    M      A01X+014250Y+116150X0200Y         S2      
017SMB_FAN0_SDA     VIA   -    M      A06X+014250Y+116150X0260Y         S2      
017SMB_FAN0_SDA           -    MD0100PA00X+014250Y+116150                       
327SMB_FAN0_SDA     R5188 -2          A01X+014542Y+116050X0198Y0197R180 S1      
327SMB_FAN7_R_SCL   R4883 -1   M      A01X+008700Y+062842X0198Y0197R090 S1      
327SMB_FAN7_R_SCL   R5274 -1          A01X+008470Y+063992X0198Y0197R090 S1      
327SMB_FAN7_R_SCL   VIA   -    M      A01X+008798Y+062304X0300Y         S1      
327SMB_FAN7_R_SCL   U321  -20         A01X+009366Y+061000X0140Y0590     S1      
327FAN_6_IMON       PR70  -2          A06X+001050Y+098042X0198Y0197R090 S2      
327FAN_6_IMON       VIA   -    M      A06X+000866Y+097481X0260Y    R180 S2      
327FAN_6_IMON       PU8   -20         A06X+001614Y+096829X0070Y0360     S2      
327FAN_6_PWM_BUF    R5517 -2          A01X+011150Y+076858X0198Y0197R090 S1      
317FAN_6_PWM_BUF    VIA   -    M      A01X+010736Y+077600X0200Y         S2      
017FAN_6_PWM_BUF    VIA   -    M      A06X+010736Y+077600X0260Y         S2      
017FAN_6_PWM_BUF          -    MD0100PA00X+010736Y+077600                       
327FAN_6_PWM_BUF    U327  -3          A01X+010324Y+077600X0280Y0360R090 S1      
327FAN_6_PWM_BUF    U401  -4   M      A01X+011194Y+077326X0160Y0200     S1      
327SMB_FAN1_R_SCL   R5278 -1          A01X+010750Y+055908X0198Y0197R270 S1      
327SMB_FAN1_R_SCL   R4790 -1   M      A01X+010750Y+056808X0198Y0197R270 S1      
327SMB_FAN1_R_SCL   VIA   -    M      A01X+009950Y+057850X0300Y         S1      
327SMB_FAN1_R_SCL   U321  -7          A01X+009878Y+058700X0140Y0590     S1      
327m0093            VIA   -    M      A01X+007200Y+062370X0300Y         S1      
327m0093            U321  -22         A01X+008854Y+061000X0140Y0590     S1      
327m0093            R5463 -2          A01X+007200Y+062842X0198Y0197R270 S1      
317m0094            J7    -4    D0380PA00X+003425Y+078350X0540Y    R270 S3      
327m0094            R5501 -1          A01X+007208Y+067900X0198Y0197R180 S1      
317m0094            VIA   -    M      A01X+006800Y+067650X0200Y    R180 S2      
017m0094            VIA   -    M      A06X+006800Y+067650X0260Y    R180 S2      
017m0094                  -    MD0100PA00X+006800Y+067650                       
327m0095            D264  -C          A01X+014867Y+114150X0220Y0240R180 S1      
327m0095            R5400 -2   M      A01X+014858Y+114640X0180Y0200R180 S1      
327m0095            VIA   -    M      A01X+015700Y+114692X0300Y         S1      
317m0095            J1    -14   D0380PA00X+016929Y+114689X0540Y    R090 S3      
327FAN_6_TIMER      PC53  -1          A06X+001850Y+098042X0198Y0197R270 S2      
327FAN_6_TIMER      PU8   -23         A06X+002087Y+096829X0070Y0360     S2      
327FAN_5_PWM_BUF    R5516 -2          A01X+010950Y+040358X0198Y0197R090 S1      
317FAN_5_PWM_BUF    VIA   -    M      A01X+010797Y+040826X0200Y         S2      
017FAN_5_PWM_BUF    VIA   -    M      A06X+010797Y+040826X0260Y         S2      
017FAN_5_PWM_BUF          -    MD0100PA00X+010797Y+040826                       
327FAN_5_PWM_BUF    U325  -3          A01X+010374Y+041100X0280Y0360R090 S1      
327FAN_5_PWM_BUF    U400  -4   M      A01X+011244Y+040826X0160Y0200     S1      
327SMB_FAN2_R_SDA   R5281 -1          A01X+011450Y+055908X0198Y0197R270 S1      
327SMB_FAN2_R_SDA   R4787 -1   M      A01X+011700Y+056808X0198Y0197R270 S1      
327SMB_FAN2_R_SDA   VIA   -    M      A01X+010900Y+057350X0300Y         S1      
327SMB_FAN2_R_SDA   U321  -8          A01X+010134Y+058700X0140Y0590     S1      
327m0096            VIA   -    M      A01X+007328Y+061676X0300Y         S1      
327m0096            R5462 -2          A01X+006800Y+062842X0198Y0197R270 S1      
327m0096            U321  -23         A01X+008598Y+061000X0140Y0590     S1      
327FAN_6_MODE       PU8   -30         A06X+003189Y+096829X0276Y0354     S2      
317FAN_6_MODE       VIA   -    M      A01X+003526Y+096880X0300Y    R180 S1      
017FAN_6_MODE       VIA   -    M      A06X+003526Y+096880X0200Y    R180 S1      
017FAN_6_MODE             -    MD0100PA00X+003526Y+096880                       
327FAN_6_MODE       PR65  -2   M      A01X+001992Y+097450X0198Y0197R180 S1      
327FAN_6_MODE       PR67  -1          A01X+002192Y+098150X0198Y0197     S1      
327FAN_4_PWM_BUF    R5515 -2          A01X+010451Y+008155X0198Y0197R180 S1      
327FAN_4_PWM_BUF    U399  -4          A01X+011344Y+007126X0160Y0200     S1      
327FAN_4_PWM_BUF    U323  -3   M      A01X+010674Y+007400X0280Y0360R090 S1      
327FAN_4_PWM_BUF    VIA   -    M      A01X+011250Y+006550X0300Y         S1      
327SMB_FAN2_R_SCL   R5280 -1          A01X+012450Y+055808X0198Y0197R270 S1      
327SMB_FAN2_R_SCL   R4791 -1          A01X+012450Y+056808X0198Y0197R270 S1      
317SMB_FAN2_R_SCL   VIA   -    M      A01X+011579Y+057379X0200Y         S2      
017SMB_FAN2_R_SCL   VIA   -    M      A06X+011579Y+057379X0260Y         S2      
017SMB_FAN2_R_SCL         -    MD0100PA00X+011579Y+057379                       
327SMB_FAN2_R_SCL   U321  -9          A01X+010390Y+058700X0140Y0590     S1      
327SMB_FAN0_R_SCL   R5276 -1          A01X+009550Y+055908X0198Y0197R270 S1      
327SMB_FAN0_R_SCL   R4789 -1   M      A01X+009300Y+056808X0198Y0197R270 S1      
327SMB_FAN0_R_SCL   VIA   -    M      A01X+009219Y+057281X0300Y         S1      
327SMB_FAN0_R_SCL   U321  -5          A01X+009366Y+058700X0140Y0590     S1      
327FAN_6_FAULT      PR64  -2          A01X+001750Y+098092X0180Y0200R090 S1      
327FAN_6_FAULT      VIA   -    M      A01X+001143Y+098305X0300Y         S1      
317FAN_6_FAULT      VIA   -    MD0100PA00X+001750Y+097450X0200Y         S0      
327FAN_6_FAULT      PU8   -22         A06X+001929Y+096829X0070Y0360     S2      
327m0097            D131  -1          A01X+013870Y+119000X0320Y0340R180 S1      
317m0097            VIA   -    M      A01X+013680Y+119480X0200Y         S2      
017m0097            VIA   -    M      A06X+013680Y+119480X0260Y         S2      
017m0097                  -    MD0100PA00X+013680Y+119480                       
327m0097            R5300 -2   M      A01X+013090Y+119250X0280Y0320R270 S1      
327m0097            R5302 -1   M      A01X+013158Y+118800X0180Y0200     S1      
327m0097            C2022 -1          A01X+013158Y+118350X0198Y0197R180 S1      
327FAN_6_SS         PC52  -1          A06X+001450Y+098042X0198Y0197R270 S2      
317FAN_6_SS         VIA   -    M      A01X+001479Y+097600X0300Y    R180 S1      
017FAN_6_SS         VIA   -    M      A06X+001479Y+097600X0200Y    R180 S1      
017FAN_6_SS               -    MD0100PA00X+001479Y+097600                       
327FAN_6_SS         PU8   -21         A06X+001772Y+096829X0070Y0360     S2      
327FAN_5_PWM        R5589 -1          A01X+005692Y+050050X0180Y0200     S1      
327FAN_5_PWM        R5613 -1   M      A01X+005692Y+050050X0180Y0200R180 S1      
317FAN_5_PWM        VIA   -    M      A01X+005692Y+050300X0200Y         S2      
017FAN_5_PWM        VIA   -    M      A06X+005692Y+050300X0260Y         S2      
017FAN_5_PWM              -    MD0100PA00X+005692Y+050300                       
327FAN_5_PWM        R5520 -2   M      A01X+011500Y+042042X0198Y0197R270 S1      
317FAN_5_PWM        VIA   -    MD0100PA00X+005850Y+044100X0200Y         S0      
327FAN_5_PWM        U400  -2          A01X+011500Y+041574X0160Y0200     S1      
327m0098            VIA   -    M      A01X+015260Y+113500X0300Y         S1      
317m0098            J1    -13   D0380PA00X+017716Y+114689X0540Y    R090 S3      
327m0098            D265  -C          A01X+014467Y+112850X0220Y0240R180 S1      
327m0098            D132  -2   M      A01X+014730Y+113500X0320Y0340     S1      
327FAN_6_FAULT_R    PR64  -1          A01X+001750Y+098408X0180Y0200R090 S1      
327FAN_6_FAULT_R    PR63  -1          A01X+002192Y+098550X0198Y0197     S1      
317SMB_FAN0_SDA_R   VIA   -    MD0100PA00X+016400Y+117150X0200Y         S0      
327SMB_FAN0_SDA_R   R5188 -1          A01X+014858Y+116050X0198Y0197R180 S1      
327SMB_FAN0_SDA_R   VIA   -    M      A01X+015700Y+116450X0300Y         S1      
317SMB_FAN0_SDA_R   J1    -7    D0380PA00X+017716Y+117051X0540Y    R090 S3      
327m0099            VIA   -    M      A01X+015260Y+119038X0300Y         S1      
317m0099            J1    -1    D0380PA00X+017716Y+119413X0540Y0540R090 S3      
327m0099            D266  -C          A01X+014867Y+118350X0220Y0240R180 S1      
327m0099            D131  -2   M      A01X+014730Y+119000X0320Y0340     S1      
327m0100            R5301 -2   M      A01X+013240Y+113750X0280Y0320R270 S1      
327m0100            R5303 -1   M      A01X+013300Y+113208X0180Y0200R090 S1      
327m0100            C2023 -1          A01X+012900Y+113208X0198Y0197R270 S1      
317m0100            VIA   -    M      A01X+013580Y+113800X0200Y         S2      
017m0100            VIA   -    M      A06X+013580Y+113800X0260Y         S2      
017m0100                  -    MD0100PA00X+013580Y+113800                       
327m0100            D132  -1          A01X+013870Y+113500X0320Y0340R180 S1      
317FAN_3_SS         VIA   -    M      A01X+013750Y+024888X0300Y         S1      
017FAN_3_SS         VIA   -    M      A06X+013750Y+024888X0200Y         S1      
017FAN_3_SS               -    MD0100PA00X+013750Y+024888                       
327FAN_3_SS         PC20  -1          A06X+013550Y+025369X0198Y0197R270 S2      
327FAN_3_SS         PU3   -21         A06X+014141Y+024152X0070Y0360     S2      
327FAN_1_TACH_OL    R5307 -2          A01X+012842Y+076200X0180Y0200     S1      
327FAN_1_TACH_OL    R5429 -1          A06X+015942Y+051650X0180Y0200     S2      
327FAN_1_TACH_OL    R5578 -1          A01X+015058Y+051700X0180Y0200R180 S1      
327FAN_1_TACH_OL    R5602 -1   M      A01X+015058Y+051700X0180Y0200     S1      
317FAN_1_TACH_OL    VIA   -    M      A01X+012565Y+077228X0200Y         S2      
017FAN_1_TACH_OL    VIA   -    M      A06X+012565Y+077228X0260Y         S2      
017FAN_1_TACH_OL          -    MD0100PA00X+012565Y+077228                       
317FAN_1_TACH_OL    VIA   -    MD0100PA00X+015058Y+051950X0200Y         S0      
317m0101            J6    -4    D0380PA00X+003425Y+042012X0540Y    R270 S3      
327m0101            R5500 -1          A01X+007208Y+067250X0198Y0197R180 S1      
317m0101            VIA   -    M      A01X+006900Y+066974X0200Y    R180 S2      
017m0101            VIA   -    M      A06X+006900Y+066974X0260Y    R180 S2      
017m0101                  -    MD0100PA00X+006900Y+066974                       
327FAN_3_CS         PR26  -1          A06X+012748Y+025365X0198Y0197R270 S2      
317FAN_3_CS         VIA   -    M      A01X+012800Y+025100X0300Y         S1      
017FAN_3_CS         VIA   -    M      A06X+012800Y+025100X0200Y         S1      
017FAN_3_CS               -    MD0100PA00X+012800Y+025100                       
327FAN_3_CS         PU3   -19         A06X+013826Y+024152X0276Y0354     S2      
327FAN_3_MODE       PR24  -2          A01X+014292Y+025300X0198Y0197R180 S1      
327FAN_3_MODE       PR43  -1   M      A01X+014292Y+024900X0198Y0197     S1      
327FAN_3_MODE       PU3   -30         A06X+015558Y+024152X0276Y0354     S2      
317FAN_3_MODE       VIA   -    M      A01X+015943Y+024483X0300Y    R180 S1      
017FAN_3_MODE       VIA   -    M      A06X+015943Y+024483X0200Y    R180 S1      
017FAN_3_MODE             -    MD0100PA00X+015943Y+024483                       
327FAN_3_TEMP       PR44  -1   M      A06X+016242Y+025369X0198Y0197R270 S2      
327FAN_3_TEMP       PC2121-1          A06X+016642Y+025369X0198Y0197R270 S2      
327FAN_3_TEMP       PU3   -29         A06X+015401Y+024152X0070Y0360     S2      
317FAN_3_TEMP       VIA   -    M      A01X+016120Y+025120X0300Y    R180 S1      
017FAN_3_TEMP       VIA   -    M      A06X+016120Y+025120X0200Y    R180 S1      
017FAN_3_TEMP             -    MD0100PA00X+016120Y+025120                       
327m0102            R4855 -2   M      A01X+001492Y+066650X0198Y0197R180 S1      
317m0102            VIA   -    MD0100PA00X+001492Y+066300X0200Y         S0      
327m0102            U7    -8          A01X+002900Y+070466X0140Y0590R270 S1      
327m0102            U392  -2          A06X+001500Y+027104X0160Y0240     S2      
317m0102            VIA   -    M      A01X+001050Y+027450X0300Y    R180 S1      
017m0102            VIA   -    M      A06X+001050Y+027450X0200Y    R180 S1      
017m0102                  -    MD0100PA00X+001050Y+027450                       
327FAN_3_CLREF      PU3   -24         A06X+014613Y+024152X0070Y0360     S2      
327FAN_3_CLREF      VIA   -    M      A06X+014613Y+024861X0260Y         S2      
327FAN_3_CLREF      PC3121-2   M      A06X+014750Y+025369X0198Y0197R090 S2      
327FAN_3_CLREF      PR45  -1          A06X+014350Y+025369X0198Y0197R270 S2      
327FAN_3_TIMER      VIA   -    M      A06X+014087Y+024909X0260Y         S2      
327FAN_3_TIMER      PC21  -1          A06X+013950Y+025369X0198Y0197R270 S2      
327FAN_3_TIMER      PU3   -23         A06X+014456Y+024152X0070Y0360     S2      
327m0103            U398  -2          A06X+006706Y+100346X0160Y0240R180 S2      
317m0103            VIA   -    MD0100PA00X+006980Y+100620X0200Y         S0      
327m0103            R4867 -2          A01X+001492Y+068600X0198Y0197R180 S1      
317m0103            VIA   -    M      A01X+001492Y+069000X0200Y         S2      
017m0103            VIA   -    M      A06X+001492Y+069000X0260Y         S2      
017m0103                  -    MD0100PA00X+001492Y+069000                       
327m0103            U7    -11         A01X+002900Y+069698X0140Y0590R270 S1      
327FAN_3_P5V        PC19  -1          A06X+015842Y+025369X0198Y0197R270 S2      
327FAN_3_P5V        PU3   -28         A06X+015243Y+024152X0070Y0360     S2      
327FAN_3_P5V        VIA   -    M      A06X+015548Y+024873X0260Y    R180 S2      
327FAN_3_P3V_R      PC18  -1          A06X+015400Y+025369X0198Y0197R270 S2      
327FAN_3_P3V_R      PU3   -27         A06X+015086Y+024152X0070Y0360     S2      
317FAN_3_P3V_R      VIA   -    M      A01X+015250Y+024950X0300Y    R180 S1      
017FAN_3_P3V_R      VIA   -    M      A06X+015250Y+024950X0200Y    R180 S1      
017FAN_3_P3V_R            -    MD0100PA00X+015250Y+024950                       
327FAN_3_P3V_R      PR21  -2          A01X+014608Y+025700X0198Y0197     S1      
327FAN_3_P3V_R      PR24  -1   M      A01X+014608Y+025300X0198Y0197R180 S1      
327FAN_3_FAULT_R    PR22  -1          A01X+013900Y+025708X0180Y0200R090 S1      
327FAN_3_FAULT_R    PR21  -1          A01X+014292Y+025700X0198Y0197     S1      
327m0104            U393  -2          A06X+006656Y+027668X0160Y0240R180 S2      
317m0104            VIA   -    MD0100PA00X+006656Y+027398X0200Y         S0      
327m0104            R4859 -2   M      A01X+001492Y+067250X0198Y0197R180 S1      
317m0104            VIA   -    M      A01X+001492Y+066900X0200Y         S2      
017m0104            VIA   -    M      A06X+001492Y+066900X0260Y         S2      
017m0104                  -    MD0100PA00X+001492Y+066900                       
327m0104            U7    -9          A01X+002900Y+070210X0140Y0590R270 S1      
327FAN_3_FAULT      PR22  -2          A01X+013900Y+025392X0180Y0200R090 S1      
327FAN_3_FAULT      VIA   -    M      A01X+013396Y+025589X0300Y         S1      
317FAN_3_FAULT      VIA   -    MD0100PA00X+014189Y+024645X0200Y         S0      
327FAN_3_FAULT      PU3   -22         A06X+014298Y+024152X0070Y0360     S2      
327m0105            U397  -2          A06X+001500Y+099854X0160Y0240     S2      
317m0105            VIA   -    MD0100PA00X+001500Y+100130X0200Y    R180 S0      
327m0105            R4863 -2          A01X+001492Y+068050X0198Y0197R180 S1      
317m0105            VIA   -    M      A01X+001250Y+067900X0200Y         S2      
017m0105            VIA   -    M      A06X+001250Y+067900X0260Y         S2      
017m0105                  -    MD0100PA00X+001250Y+067900                       
327m0105            U7    -10         A01X+002900Y+069954X0140Y0590R270 S1      
327FAN_1_OK_R_LED   R5096 -2          A01X+017308Y+067650X0198Y0197     S1      
317FAN_1_OK_R_LED   VIA   -    M      A01X+017900Y+067650X0300Y         S1      
017FAN_1_OK_R_LED   VIA   -    M      A06X+017900Y+067650X0200Y         S1      
017FAN_1_OK_R_LED         -    MD0100PA00X+017900Y+067650                       
327FAN_1_OK_R_LED   R5391 -2   M      A01X+012700Y+078408X0198Y0197R090 S1      
317FAN_1_OK_R_LED   VIA   -    MD0100PA00X+012850Y+078650X0200Y         S0      
327FAN_1_OK_R_LED   U370  -G          A01X+013335Y+078526X0240Y0320R270 S1      
327FAN_3_IMON       PR46  -2          A06X+013150Y+025369X0198Y0197R090 S2      
327FAN_3_IMON       PU3   -20         A06X+013983Y+024152X0070Y0360     S2      
327FAN_3_IMON       VIA   -    M      A06X+013398Y+024917X0260Y    R180 S2      
317FAN_0_OK_R_LED   VIA   -    MD0100PA00X+014560Y+083810X0200Y         S0      
317FAN_0_OK_R_LED   VIA   -    MD0100PA00X+012050Y+084500X0200Y         S0      
327FAN_0_OK_R_LED   R5384 -2   M      A01X+012700Y+114858X0198Y0197R090 S1      
317FAN_0_OK_R_LED   VIA   -    MD0100PA00X+012450Y+114858X0200Y         S0      
327FAN_0_OK_R_LED   U368  -G          A01X+013235Y+114856X0240Y0320R270 S1      
327FAN_0_OK_R_LED   R5094 -2          A01X+017308Y+066850X0198Y0197     S1      
317FAN_0_OK_R_LED   VIA   -    M      A01X+017548Y+066850X0200Y         S2      
017FAN_0_OK_R_LED   VIA   -    M      A06X+017548Y+066850X0260Y         S2      
017FAN_0_OK_R_LED         -    MD0100PA00X+017548Y+066850                       
317m0106            J5    -4    D0380PA00X+003425Y+005673X0540Y    R270 S3      
327m0106            R5499 -1          A01X+007208Y+066650X0198Y0197R180 S1      
317m0106            VIA   -    M      A01X+006800Y+066400X0200Y    R180 S2      
017m0106            VIA   -    M      A06X+006800Y+066400X0260Y    R180 S2      
017m0106                  -    MD0100PA00X+006800Y+066400                       
327FAN_6_OK_R_LED   R5107 -2          A01X+011242Y+068350X0198Y0197R180 S1      
317FAN_6_OK_R_LED   VIA   -    MD0100PA00X+007672Y+074950X0200Y         S0      
327FAN_6_OK_R_LED   R5371 -2   M      A01X+007700Y+081342X0198Y0197R270 S1      
317FAN_6_OK_R_LED   VIA   -    M      A01X+008300Y+081000X0200Y    R180 S2      
017FAN_6_OK_R_LED   VIA   -    M      A06X+008300Y+081000X0260Y    R180 S2      
017FAN_6_OK_R_LED         -    MD0100PA00X+008300Y+081000                       
327FAN_6_OK_R_LED   U364  -G          A01X+007165Y+081294X0240Y0320R090 S1      
327FAN_4_OK_R_LED   U340  -G          A01X+007165Y+010344X0240Y0320R090 S1      
317FAN_4_OK_R_LED   VIA   -    MD0100PA00X+007950Y+010442X0200Y    R180 S0      
327FAN_4_OK_R_LED   R4990 -2   M      A01X+007700Y+010442X0198Y0197R270 S1      
317FAN_4_OK_R_LED   VIA   -    M      A01X+013358Y+069200X0200Y    R180 S2      
017FAN_4_OK_R_LED   VIA   -    M      A06X+013358Y+069200X0260Y    R180 S2      
017FAN_4_OK_R_LED         -    MD0100PA00X+013358Y+069200                       
327FAN_4_OK_R_LED   R5102 -2          A01X+013358Y+069450X0198Y0197     S1      
327m0107            VIA   -    M      A01X+013870Y+005770X0300Y         S1      
327m0107            C2055 -1          A01X+014350Y+005808X0198Y0197R270 S1      
327m0107            D143  -1          A01X+013820Y+006400X0320Y0340R180 S1      
327m0107            R5325 -2   M      A01X+013240Y+005950X0280Y0320R270 S1      
327m0107            R5327 -1   M      A01X+013308Y+006500X0180Y0200     S1      
317FAN_3_OK_R_LED   VIA   -    M      A01X+017900Y+069400X0200Y         S2      
017FAN_3_OK_R_LED   VIA   -    M      A06X+017900Y+069400X0260Y         S2      
017FAN_3_OK_R_LED         -    MD0100PA00X+017900Y+069400                       
327FAN_3_OK_R_LED   R5100 -2          A01X+017308Y+069250X0198Y0197     S1      
327FAN_3_OK_R_LED   U375  -G          A01X+013235Y+007556X0240Y0320R270 S1      
317FAN_3_OK_R_LED   VIA   -    MD0100PA00X+012700Y+007750X0200Y         S0      
327FAN_3_OK_R_LED   R5395 -2   M      A01X+012700Y+007458X0198Y0197R090 S1      
327SMB_FAN3_SDA_R   R5244 -1          A01X+014858Y+009884X0198Y0197R180 S1      
317SMB_FAN3_SDA_R   J4    -7    D0380PA00X+017716Y+008035X0540Y    R090 S3      
327SMB_FAN3_SDA_R   VIA   -    M      A01X+015700Y+009300X0300Y         S1      
327m0108            R5095 -2          A01X+017308Y+067250X0198Y0197     S1      
317m0108            VIA   -    MD0100PA00X+017550Y+067250X0200Y         S0      
317m0108            VIA   -    MD0100PA00X+014828Y+083888X0200Y         S0      
317m0108            VIA   -    M      A01X+010450Y+083450X0200Y         S2      
017m0108            VIA   -    M      A06X+010450Y+083450X0260Y         S2      
017m0108                  -    MD0100PA00X+010450Y+083450                       
327m0108            R5387 -2   M      A01X+012700Y+116258X0198Y0197R090 S1      
317m0108            VIA   -    MD0100PA00X+012700Y+116600X0200Y         S0      
327m0108            U369  -G          A01X+013235Y+116456X0240Y0320R270 S1      
317FAN_3_PWM_IL_R   J4    -3    D0380PA00X+017716Y+009610X0540Y    R090 S3      
327FAN_3_PWM_IL_R   VIA   -    M      A01X+015320Y+010784X0300Y         S1      
327FAN_3_PWM_IL_R   R5240 -1   M      A01X+014858Y+010784X0198Y0197R180 S1      
327FAN_3_PWM_IL_R   C2053 -1   M      A01X+014008Y+010784X0198Y0197R180 S1      
327FAN_3_PWM_IL_R   D286  -C          A01X+013117Y+010773X0220Y0240R180 S1      
327m0109            R5097 -2          A01X+017308Y+068050X0198Y0197     S1      
317m0109            VIA   -    M      A01X+017750Y+067950X0200Y         S2      
017m0109            VIA   -    M      A06X+017750Y+067950X0260Y         S2      
017m0109                  -    MD0100PA00X+017750Y+067950                       
327m0109            R5389 -2   M      A01X+012700Y+079708X0198Y0197R090 S1      
317m0109            VIA   -    MD0100PA00X+013237Y+078887X0200Y         S0      
327m0109            U371  -G          A01X+013235Y+080106X0240Y0320R270 S1      
327m0110            R5324 -2          A01X+012250Y+011090X0280Y0320     S1      
327m0110            R5326 -1   M      A01X+013108Y+011400X0180Y0200     S1      
317m0110            VIA   -    M      A01X+013500Y+012050X0200Y         S2      
017m0110            VIA   -    M      A06X+013500Y+012050X0260Y         S2      
017m0110                  -    MD0100PA00X+013500Y+012050                       
327m0110            C2054 -1   M      A01X+013108Y+011800X0198Y0197R180 S1      
327m0110            D141  -1          A01X+013870Y+011934X0320Y0340R180 S1      
327m0111            R5099 -2          A01X+017308Y+068850X0198Y0197     S1      
317m0111            VIA   -    MD0100PA00X+018250Y+068800X0200Y         S0      
327m0111            R5399 -2   M      A01X+012758Y+043500X0198Y0197     S1      
317m0111            VIA   -    M      A01X+013050Y+043250X0200Y         S2      
017m0111            VIA   -    M      A06X+013050Y+043250X0260Y         S2      
017m0111                  -    MD0100PA00X+013050Y+043250                       
327m0111            U373  -G          A01X+013285Y+043506X0240Y0320R270 S1      
327m0112            D283  -C   M      A01X+014850Y+005817X0220Y0240R270 S1      
317m0112            J4    -13   D0380PA00X+017716Y+005673X0540Y    R090 S3      
327m0112            VIA   -    M      A01X+015700Y+005298X0300Y         S1      
327m0112            D143  -2          A01X+014680Y+006400X0320Y0340     S1      
327FAN_7_OK_R_LED   R5378 -2   M      A01X+007650Y+117342X0198Y0197R270 S1      
317FAN_7_OK_R_LED   VIA   -    MD0100PA00X+007900Y+117342X0200Y    R180 S0      
327FAN_7_OK_R_LED   U366  -G          A01X+007115Y+117344X0240Y0320R090 S1      
327FAN_7_OK_R_LED   R5110 -2          A01X+011242Y+067550X0198Y0197R180 S1      
317FAN_7_OK_R_LED   VIA   -    M      A01X+010131Y+067550X0200Y    R180 S2      
017FAN_7_OK_R_LED   VIA   -    M      A06X+010131Y+067550X0260Y    R180 S2      
017FAN_7_OK_R_LED         -    MD0100PA00X+010131Y+067550                       
317m0113            J4    -1    D0380PA00X+017716Y+010398X0540Y0540R090 S3      
327m0113            VIA   -    M      A01X+015660Y+011460X0300Y         S1      
327m0113            D284  -C   M      A01X+014467Y+011284X0220Y0240R180 S1      
327m0113            D141  -2          A01X+014730Y+011934X0320Y0340     S1      
327FAN_2_OK_R_LED   R5393 -2          A01X+012750Y+042158X0198Y0197R090 S1      
317FAN_2_OK_R_LED   VIA   -    MD0100PA00X+013285Y+042184X0200Y         S0      
327FAN_2_OK_R_LED   U372  -G   M      A01X+013285Y+041906X0240Y0320R270 S1      
327FAN_2_OK_R_LED   R5098 -2          A01X+017308Y+068450X0198Y0197     S1      
317FAN_2_OK_R_LED   VIA   -    M      A01X+018050Y+068450X0300Y         S1      
017FAN_2_OK_R_LED   VIA   -    M      A06X+018050Y+068450X0200Y         S1      
017FAN_2_OK_R_LED         -    MD0100PA00X+018050Y+068450                       
327m0114            R5362 -2   M      A01X+007700Y+043242X0198Y0197R270 S1      
317m0114            VIA   -    MD0100PA00X+007946Y+042996X0200Y    R180 S0      
327m0114            U363  -G          A01X+007165Y+043244X0240Y0320R090 S1      
327m0114            R5105 -2          A01X+011242Y+068750X0198Y0197R180 S1      
317m0114            VIA   -    M      A01X+011750Y+068990X0200Y         S2      
017m0114            VIA   -    M      A06X+011750Y+068990X0260Y         S2      
017m0114                  -    MD0100PA00X+011750Y+068990                       
317m0115            VIA   -    M      A01X+018100Y+069650X0300Y         S1      
017m0115            VIA   -    M      A06X+018100Y+069650X0200Y         S1      
017m0115                  -    MD0100PA00X+018100Y+069650                       
327m0115            R5101 -2          A01X+017308Y+069650X0198Y0197     S1      
327m0115            R5397 -2          A01X+012700Y+008858X0198Y0197R090 S1      
327m0115            U374  -G   M      A01X+013235Y+009156X0240Y0320R270 S1      
317m0115            VIA   -    MD0100PA00X+013235Y+009427X0200Y         S0      
317SMB_FAN3_SCL_R   J4    -6    D0380PA00X+016929Y+008823X0540Y    R090 S3      
327SMB_FAN3_SCL_R   VIA   -    M      A01X+015700Y+010100X0300Y         S1      
327SMB_FAN3_SCL_R   R5242 -2          A01X+014858Y+010334X0198Y0197     S1      
327m0116            R5108 -2          A01X+011242Y+067950X0198Y0197R180 S1      
317m0116            VIA   -    MD0100PA00X+007998Y+073998X0200Y         S0      
327m0116            R5370 -2   M      A01X+007700Y+080042X0198Y0197R270 S1      
327m0116            U365  -G          A01X+007165Y+079694X0240Y0320R090 S1      
317m0116            VIA   -    M      A01X+008300Y+080400X0200Y    R180 S2      
017m0116            VIA   -    M      A06X+008300Y+080400X0260Y    R180 S2      
017m0116                  -    MD0100PA00X+008300Y+080400                       
327m0117            R5498 -1          A01X+007208Y+065750X0198Y0197R180 S1      
317m0117            VIA   -    M      A01X+019126Y+054750X0200Y         S2      
017m0117            VIA   -    M      A06X+019126Y+054750X0260Y         S2      
017m0117                  -    MD0100PA00X+019126Y+054750                       
317m0117            J4    -4    D0380PA00X+016929Y+009610X0540Y    R090 S3      
317m0118            VIA   -    M      A01X+010128Y+067150X0300Y    R180 S1      
017m0118            VIA   -    M      A06X+010128Y+067150X0200Y    R180 S1      
017m0118                  -    MD0100PA00X+010128Y+067150                       
327m0118            R5111 -2          A01X+011242Y+067150X0198Y0197R180 S1      
327m0118            R5379 -2   M      A01X+007650Y+115742X0198Y0197R270 S1      
317m0118            VIA   -    MD0100PA00X+007900Y+115742X0200Y    R180 S0      
327m0118            U367  -G          A01X+007115Y+115744X0240Y0320R090 S1      
327FAN_3_PWM_OL_R   D285  -C          A01X+013367Y+012450X0220Y0240R180 S1      
327FAN_3_PWM_OL_R   C2052 -1   M      A01X+014158Y+012684X0198Y0197R180 S1      
327FAN_3_PWM_OL_R   R5236 -2   M      A01X+014908Y+012684X0198Y0197     S1      
317FAN_3_PWM_OL_R   J4    -2    D0380PA00X+016929Y+010398X0540Y    R090 S3      
327FAN_3_PWM_OL_R   VIA   -    M      A01X+015412Y+012458X0300Y         S1      
327FAN_5_OK_R_LED   R5104 -2          A01X+011242Y+069300X0198Y0197R180 S1      
317FAN_5_OK_R_LED   VIA   -    MD0100PA00X+011800Y+069600X0200Y    R180 S0      
327FAN_5_OK_R_LED   R5363 -2   M      A01X+007700Y+044992X0198Y0197R270 S1      
317FAN_5_OK_R_LED   VIA   -    M      A01X+007950Y+044992X0200Y    R180 S2      
017FAN_5_OK_R_LED   VIA   -    M      A06X+007950Y+044992X0260Y    R180 S2      
017FAN_5_OK_R_LED         -    MD0100PA00X+007950Y+044992                       
327FAN_5_OK_R_LED   U362  -G          A01X+007165Y+044894X0240Y0320R090 S1      
317m0119            VIA   -    MD0100PA00X+015400Y+047100X0200Y         S0      
327m0119            R5460 -1          A01X+010208Y+047850X0198Y0197R180 S1      
317m0119            VIA   -    MD0100PA00X+010450Y+047850X0200Y         S0      
317m0119            VIA   -    MD0100PA00X+019150Y+052950X0200Y         S0      
327m0119            R5557 -1          A01X+019158Y+053200X0198Y0197R180 S1      
317m0119            VIA   -    MD0100PA00X+010900Y+054350X0200Y         S0      
327m0119            R5458 -1          A01X+011000Y+053458X0198Y0197R270 S1      
317m0119            VIA   -    MD0100PA00X+007540Y+054450X0200Y         S0      
317m0119            VIA   -    MD0100PA00X+007408Y+072650X0200Y         S0      
327m0119            R5466 -1   M      A01X+007408Y+072400X0198Y0197R180 S1      
327m0119            R313  -2          A01X+007408Y+073450X0198Y0197     S1      
327m0119            R5462 -1          A01X+006800Y+063158X0198Y0197R270 S1      
317m0119            VIA   -    MD0100PA00X+007868Y+063732X0200Y    R090 S0      
327m0119            R5469 -1          A01X+011242Y+065950X0198Y0197     S1      
317m0119            VIA   -    M      A01X+009503Y+066000X0200Y         S2      
017m0119            VIA   -    M      A06X+009503Y+066000X0260Y         S2      
017m0119                  -    MD0100PA00X+009503Y+066000                       
327m0119            R5568 -1          A01X+001900Y+053408X0198Y0197R270 S1      
317m0119            VIA   -    MD0100PA00X+009988Y+005750X0200Y         S0      
327m0119            R4969 -1          A01X+010250Y+005628X0198Y0197R270 S1      
327m0120            R5329 -2          A01X+013268Y+039950X0280Y0320R270 S1      
327m0120            R5331 -1   M      A01X+013258Y+040373X0180Y0200     S1      
327m0120            C2043 -1   M      A01X+013258Y+040800X0198Y0197R180 S1      
327m0120            D139  -1          A01X+013870Y+040723X0320Y0340R180 S1      
317m0120            VIA   -    M      A01X+013524Y+040723X0200Y         S2      
017m0120            VIA   -    M      A06X+013524Y+040723X0260Y         S2      
017m0120                  -    MD0100PA00X+013524Y+040723                       
317m0121            VIA   -    MD0100PA00X+007950Y+008692X0200Y    R180 S0      
327m0121            U342  -G          A01X+007165Y+008644X0240Y0320R090 S1      
327m0121            R4992 -2   M      A01X+007700Y+008692X0198Y0197R270 S1      
317m0121            VIA   -    M      A01X+012800Y+069450X0200Y         S2      
017m0121            VIA   -    M      A06X+012800Y+069450X0260Y         S2      
017m0121                  -    MD0100PA00X+012800Y+069450                       
327m0121            R5103 -2          A01X+012558Y+069450X0198Y0197     S1      
327SMB_FAN2_SDA_R   VIA   -    M      A01X+015700Y+044273X0300Y         S1      
327SMB_FAN2_SDA_R   R5224 -1          A01X+014858Y+044273X0198Y0197R180 S1      
317SMB_FAN2_SDA_R   J3    -7    D0380PA00X+017716Y+044374X0540Y    R090 S3      
327PCA9552_MB1_A2   R5114 -2   M      A01X+016992Y+066350X0198Y0197R180 S1      
327PCA9552_MB1_A2   R5117 -1          A01X+018092Y+066350X0198Y0197     S1      
317PCA9552_MB1_A2   VIA   -    M      A01X+016655Y+066350X0200Y         S2      
017PCA9552_MB1_A2   VIA   -    M      A06X+016655Y+066350X0260Y         S2      
017PCA9552_MB1_A2         -    MD0100PA00X+016655Y+066350                       
327PCA9552_MB1_A2   U8    -3          A01X+015450Y+066654X0140Y0590R090 S1      
317m0122            VIA   -    MD0100PA00X+019158Y+052400X0200Y         S0      
327m0122            R5558 -1          A01X+019158Y+052650X0198Y0197R180 S1      
317m0122            VIA   -    MD0100PA00X+010800Y+053950X0200Y         S0      
327m0122            R5459 -1          A01X+010600Y+053458X0198Y0197R270 S1      
317m0122            VIA   -    MD0100PA00X+007250Y+054150X0200Y         S0      
317m0122            VIA   -    MD0100PA00X+009153Y+066326X0200Y         S0      
327m0122            R5468 -1          A01X+011242Y+066350X0198Y0197     S1      
317m0122            VIA   -    MD0100PA00X+007408Y+072150X0200Y         S0      
327m0122            R5467 -1   M      A01X+007408Y+071900X0198Y0197R180 S1      
327m0122            R314  -2          A01X+007408Y+073850X0198Y0197     S1      
317m0122            VIA   -    MD0100PA00X+007846Y+063401X0200Y    R090 S0      
327m0122            R5463 -1          A01X+007200Y+063158X0198Y0197R270 S1      
327m0122            R5569 -1          A01X+002300Y+053408X0198Y0197R270 S1      
317m0122            VIA   -    MD0100PA00X+015164Y+047620X0200Y         S0      
327m0122            R5461 -1          A01X+010208Y+048342X0198Y0197R180 S1      
317m0122            VIA   -    MD0100PA00X+010450Y+048342X0200Y         S0      
317m0122            VIA   -    M      A01X+009900Y+006100X0200Y         S2      
017m0122            VIA   -    M      A06X+009900Y+006100X0260Y         S2      
017m0122                  -    MD0100PA00X+009900Y+006100                       
327m0122            R4968 -1          A01X+009600Y+005628X0198Y0197R270 S1      
327FAN_0_PWM_OL_R   D267  -C          A01X+013117Y+119800X0220Y0240R180 S1      
327FAN_0_PWM_OL_R   VIA   -    M      A01X+015750Y+119750X0300Y         S1      
317FAN_0_PWM_OL_R   J1    -2    D0380PA00X+016929Y+119413X0540Y    R090 S3      
327FAN_0_PWM_OL_R   R5184 -2   M      A01X+014908Y+119750X0198Y0197     S1      
327FAN_0_PWM_OL_R   C2020 -1   M      A01X+014058Y+119750X0198Y0197R180 S1      
327FAN_2_PWM_IL_R   VIA   -    M      A01X+015700Y+045574X0300Y         S1      
317FAN_2_PWM_IL_R   J3    -3    D0380PA00X+017716Y+045949X0540Y    R090 S3      
327FAN_2_PWM_IL_R   C2041 -1          A01X+014008Y+045173X0198Y0197R180 S1      
327FAN_2_PWM_IL_R   R5220 -1   M      A01X+014858Y+045173X0198Y0197R180 S1      
327FAN_2_PWM_IL_R   D280  -C          A01X+013117Y+045161X0220Y0240R180 S1      
327PCA9552_MB1_A1   R5113 -2   M      A01X+016992Y+065950X0198Y0197R180 S1      
327PCA9552_MB1_A1   R5116 -1          A01X+018092Y+065950X0198Y0197     S1      
317PCA9552_MB1_A1   VIA   -    M      A01X+017198Y+065685X0200Y         S2      
017PCA9552_MB1_A1   VIA   -    M      A06X+017198Y+065685X0260Y         S2      
017PCA9552_MB1_A1         -    MD0100PA00X+017198Y+065685                       
327PCA9552_MB1_A1   U8    -2          A01X+015450Y+066398X0140Y0590R090 S1      
327m0123            R5328 -2   M      A01X+013090Y+046100X0280Y0320R270 S1      
327m0123            R5330 -1   M      A01X+013158Y+046550X0180Y0200     S1      
327m0123            D137  -1          A01X+013870Y+046300X0320Y0340R180 S1      
317m0123            VIA   -    M      A01X+013500Y+046300X0200Y         S2      
017m0123            VIA   -    M      A06X+013500Y+046300X0260Y         S2      
017m0123                  -    MD0100PA00X+013500Y+046300                       
327m0123            C2042 -1          A01X+013158Y+045673X0198Y0197R180 S1      
327PCA9552_MB1_A0   R5112 -2          A01X+016992Y+065150X0198Y0197R180 S1      
327PCA9552_MB1_A0   R5115 -1          A01X+018092Y+065200X0198Y0197     S1      
327PCA9552_MB1_A0   VIA   -    M      A01X+016415Y+065737X0300Y         S1      
327PCA9552_MB1_A0   U8    -1          A01X+015450Y+066142X0140Y0590R090 S1      
327m0124            D277  -C          A01X+014467Y+040073X0220Y0240R180 S1      
327m0124            VIA   -    M      A01X+015450Y+041000X0300Y         S1      
317m0124            J3    -13   D0380PA00X+017716Y+042012X0540Y    R090 S3      
327m0124            D139  -2   M      A01X+014730Y+040723X0320Y0340     S1      
317m0125            J3    -1    D0380PA00X+017716Y+046736X0540Y0540R090 S3      
327m0125            VIA   -    M      A01X+015260Y+046361X0300Y         S1      
327m0125            D278  -C          A01X+014467Y+045673X0220Y0240R180 S1      
327m0125            D137  -2   M      A01X+014730Y+046300X0320Y0340     S1      
327SMB_FAN2_SCL_R   R5222 -2          A01X+014858Y+044723X0198Y0197     S1      
327SMB_FAN2_SCL_R   VIA   -    M      A01X+015332Y+044925X0300Y         S1      
317SMB_FAN2_SCL_R   J3    -6    D0380PA00X+016929Y+045161X0540Y    R090 S3      
317m0126            J3    -4    D0380PA00X+016929Y+045949X0540Y    R090 S3      
327m0126            R5497 -1          A01X+007208Y+065150X0198Y0197R180 S1      
317m0126            VIA   -    M      A01X+018750Y+064350X0300Y         S1      
017m0126            VIA   -    M      A06X+018750Y+064350X0200Y         S1      
017m0126                  -    MD0100PA00X+018750Y+064350                       
327FAN_2_PWM_OL_R   C2040 -1   M      A01X+014058Y+047073X0198Y0197R180 S1      
327FAN_2_PWM_OL_R   VIA   -    M      A01X+015700Y+046850X0300Y         S1      
317FAN_2_PWM_OL_R   J3    -2    D0380PA00X+016929Y+046736X0540Y    R090 S3      
327FAN_2_PWM_OL_R   R5216 -2   M      A01X+014908Y+047073X0198Y0197     S1      
327FAN_2_PWM_OL_R   D279  -C          A01X+013167Y+047073X0220Y0240R180 S1      
327m0127            R5305 -2   M      A01X+013790Y+076650X0280Y0320R270 S1      
327m0127            R5307 -1          A01X+013158Y+076200X0180Y0200     S1      
327m0127            C2031 -1   M      A01X+013542Y+076200X0198Y0197     S1      
327m0127            D135  -1          A01X+013820Y+077311X0320Y0340R180 S1      
327SMB_FAN1_SDA_R   VIA   -    M      A01X+015330Y+080611X0300Y         S1      
317SMB_FAN1_SDA_R   J2    -7    D0380PA00X+017716Y+080713X0540Y    R090 S3      
327SMB_FAN1_SDA_R   R5204 -1          A01X+014858Y+080611X0198Y0197R180 S1      
327FAN_1_PWM_IL_R   VIA   -    M      A01X+015700Y+081911X0300Y         S1      
317FAN_1_PWM_IL_R   J2    -3    D0380PA00X+017716Y+082287X0540Y    R090 S3      
327FAN_1_PWM_IL_R   C2029 -1          A01X+014008Y+081511X0198Y0197R180 S1      
327FAN_1_PWM_IL_R   R5200 -1   M      A01X+014858Y+081511X0198Y0197R180 S1      
327FAN_1_PWM_IL_R   D274  -C          A01X+013117Y+081500X0220Y0240R180 S1      
327m0128            R5304 -2   M      A01X+013190Y+082911X0280Y0320R270 S1      
327m0128            R5306 -1   M      A01X+013158Y+082461X0180Y0200     S1      
327m0128            C2030 -1          A01X+013158Y+082011X0198Y0197R180 S1      
317m0128            VIA   -    M      A01X+013480Y+082661X0200Y         S2      
017m0128            VIA   -    M      A06X+013480Y+082661X0260Y         S2      
017m0128                  -    MD0100PA00X+013480Y+082661                       
327m0128            D133  -1          A01X+013870Y+082661X0320Y0340R180 S1      
327m0129            VIA   -    M      A01X+015227Y+077343X0300Y         S1      
317m0129            J2    -13   D0380PA00X+017716Y+078350X0540Y    R090 S3      
327m0129            D271  -C          A01X+014817Y+076650X0220Y0240R180 S1      
327m0129            D135  -2   M      A01X+014680Y+077311X0320Y0340     S1      
327m0130            VIA   -    M      A01X+015580Y+082700X0300Y         S1      
317m0130            J2    -1    D0380PA00X+017716Y+083075X0540Y0540R090 S3      
327m0130            D272  -C          A01X+014467Y+082011X0220Y0240R180 S1      
327m0130            D133  -2   M      A01X+014730Y+082661X0320Y0340     S1      
327TP_U7_PIN16      U7    -16         A01X+005200Y+070210X0140Y0590R270 S1      
327FRU_WP_N         R309  -1          A01X+007092Y+074650X0180Y0200R180 S1      
327FRU_WP_N         R308  -2   M      A01X+007092Y+074250X0198Y0197R180 S1      
327FRU_WP_N         VIA   -    M      A01X+006509Y+074709X0300Y         S1      
327FRU_WP_N         U59   -7          A01X+005090Y+074550X0220Y0680R270 S1      
327SMB_FRU_DAT      R313  -1          A01X+007092Y+073450X0198Y0197     S1      
317SMB_FRU_DAT      VIA   -    M      A01X+006557Y+073450X0200Y         S2      
017SMB_FRU_DAT      VIA   -    M      A06X+006557Y+073450X0260Y         S2      
017SMB_FRU_DAT            -    MD0100PA00X+006557Y+073450                       
327SMB_FRU_DAT      U59   -5          A01X+005090Y+073550X0220Y0680R270 S1      
327SMB_FAN1_SCL_R   VIA   -    M      A01X+015417Y+081267X0300Y         S1      
317SMB_FAN1_SCL_R   J2    -6    D0380PA00X+016929Y+081500X0540Y    R090 S3      
327SMB_FAN1_SCL_R   R5202 -2          A01X+014858Y+081061X0198Y0197     S1      
327FRU_ADDR1        R311  -2   M      A01X+002308Y+074100X0198Y0197     S1      
327FRU_ADDR1        R316  -2          A01X+001258Y+074100X0198Y0197     S1      
317FRU_ADDR1        VIA   -    M      A01X+001746Y+073718X0200Y         S2      
017FRU_ADDR1        VIA   -    M      A06X+001746Y+073718X0260Y         S2      
017FRU_ADDR1              -    MD0100PA00X+001746Y+073718                       
327FRU_ADDR1        U59   -2          A01X+003010Y+074550X0220Y0680R270 S1      
317m0131            J2    -4    D0380PA00X+016929Y+082287X0540Y    R090 S3      
327m0131            R5496 -1          A01X+007208Y+064700X0198Y0197R180 S1      
317m0131            VIA   -    M      A01X+018250Y+064160X0200Y         S2      
017m0131            VIA   -    M      A06X+018250Y+064160X0260Y         S2      
017m0131                  -    MD0100PA00X+018250Y+064160                       
327FRU_ADDR0        R312  -2   M      A01X+002308Y+074800X0198Y0197     S1      
327FRU_ADDR0        R317  -2          A01X+001258Y+074800X0198Y0197     S1      
317FRU_ADDR0        VIA   -    M      A01X+001501Y+074556X0200Y         S2      
017FRU_ADDR0        VIA   -    M      A06X+001501Y+074556X0260Y         S2      
017FRU_ADDR0              -    MD0100PA00X+001501Y+074556                       
327FRU_ADDR0        U59   -1          A01X+003010Y+075050X0220Y0680R270 S1      
327FAN_1_PWM_OL_R   VIA   -    M      A01X+015690Y+083411X0300Y         S1      
317FAN_1_PWM_OL_R   J2    -2    D0380PA00X+016929Y+083075X0540Y    R090 S3      
327FAN_1_PWM_OL_R   R5196 -2   M      A01X+014908Y+083411X0198Y0197     S1      
327FAN_1_PWM_OL_R   C2028 -1   M      A01X+014058Y+083411X0198Y0197R180 S1      
327FAN_1_PWM_OL_R   D273  -C          A01X+013217Y+083450X0220Y0240R180 S1      
327FRU_ADDR2        R310  -2   M      A01X+002308Y+073400X0198Y0197     S1      
327FRU_ADDR2        R315  -2          A01X+001258Y+073400X0198Y0197     S1      
317FRU_ADDR2        VIA   -    M      A01X+001338Y+073027X0200Y         S2      
017FRU_ADDR2        VIA   -    M      A06X+001338Y+073027X0260Y         S2      
017FRU_ADDR2              -    MD0100PA00X+001338Y+073027                       
327FRU_ADDR2        U59   -3          A01X+003010Y+074050X0220Y0680R270 S1      
327SMB_FRU_CLK      R314  -1          A01X+007092Y+073850X0198Y0197     S1      
317SMB_FRU_CLK      VIA   -    M      A01X+005861Y+074050X0200Y         S2      
017SMB_FRU_CLK      VIA   -    M      A06X+005861Y+074050X0260Y         S2      
017SMB_FRU_CLK            -    MD0100PA00X+005861Y+074050                       
327SMB_FRU_CLK      U59   -6          A01X+005090Y+074050X0220Y0680R270 S1      
327GND              C2019 -1          A01X+018958Y+121500X0180Y0200     S1      
327GND              C2025 -1          A01X+019750Y+087258X0180Y0200R090 S1      
327GND              C2037 -1          A01X+019008Y+049000X0180Y0200     S1      
327GND              C2049 -1          A01X+019485Y+014451X0180Y0200R090 S1      
327GND              C2012 -1          A01X+000890Y+014251X0180Y0200R090 S1      
327GND              C2027 -1          A01X+001508Y+049100X0180Y0200     S1      
327GND              C2039 -1          A01X+001060Y+086608X0180Y0200R090 S1      
327GND              C2051 -1          A01X+001392Y+121500X0180Y0200R180 S1      
327GND              D283  -A          A01X+014850Y+005483X0220Y0240R090 S1      
327GND              C2124 -2          A01X+008230Y+012690X0280Y0320     S1      
327GND              C2123 -2   M      A01X+010460Y+012100X0280Y0320R090 S1      
327GND              GF1   -S6         A01X+008799Y+001713X0320Y1970     S1      
327GND              GF1   -S5         A01X+008299Y+001713X0320Y1970     S1      
327GND              GF1   -P3_P       A01X+011677Y+001968X1730Y2480     S1      
327GND              C2054 -2   M      A01X+012792Y+011800X0198Y0197R180 S1      
327GND              D284  -A          A01X+014133Y+011284X0220Y0240     S1      
327GND              C2053 -2          A01X+013692Y+010784X0198Y0197R180 S1      
327GND              D281  -A          A01X+014533Y+009400X0220Y0240     S1      
327GND              D286  -A          A01X+012783Y+010773X0220Y0240     S1      
327GND              D282  -A          A01X+014533Y+007984X0220Y0240     S1      
327GND              U374  -S          A01X+013235Y+008644X0240Y0320R270 S1      
327GND              U399  -3          A01X+011344Y+007874X0160Y0200     S1      
327GND              D241  -A          A01X+006272Y+012684X0220Y0240R180 S1      
327GND              R5666 -2          A01X+010000Y+012258X0198Y0197R090 S1      
327GND              C2017 -2   M      A01X+007550Y+012758X0198Y0197R090 S1      
327GND              U66   -3          A01X+009106Y+009726X0160Y0200R180 S1      
327GND              C2089 -2          A01X+008550Y+011258X0198Y0197R090 S1      
327GND              U340  -S          A01X+007165Y+010856X0240Y0320R090 S1      
327GND              U342  -S          A01X+007165Y+009156X0240Y0320R090 S1      
327GND              C2015 -2          A01X+006662Y+007534X0198Y0197     S1      
327GND              D243  -A          A01X+007522Y+005634X0220Y0240R180 S1      
327GND              D242  -A          A01X+006222Y+007034X0220Y0240R180 S1      
327GND              C2014 -2          A01X+006454Y+005477X0198Y0197R270 S1      
327GND              D240  -A          A01X+005867Y+011369X0220Y0240R180 S1      
327GND              D239  -A          A01X+005867Y+009750X0220Y0240R180 S1      
317GND              VIA   -    MD0100PA00X+012592Y+003730X0200Y         S0      
317GND              VIA   -    MD0100PA00X+012292Y+003730X0200Y         S0      
317GND              VIA   -    MD0100PA00X+012592Y+003980X0200Y         S0      
317GND              VIA   -    MD0100PA00X+012292Y+003980X0200Y         S0      
317GND              VIA   -    MD0100PA00X+008550Y+003300X0200Y         S0      
317GND              VIA   -    MD0100PA00X+008550Y+003650X0200Y         S0      
317GND              VIA   -    MD0100PA00X+008550Y+004000X0200Y         S0      
317GND              VIA   -    MD0100PA00X+007840Y+003320X0200Y         S0      
317GND              VIA   -    MD0100PA00X+007840Y+003670X0200Y         S0      
317GND              VIA   -    MD0100PA00X+007840Y+004020X0200Y         S0      
317GND              VIA   -    MD0100PA00X+012550Y+011800X0200Y         S0      
317GND              VIA   -    MD0100PA00X+014133Y+011554X0200Y         S0      
317GND              VIA   -    MD0100PA00X+013452Y+010784X0200Y         S0      
317GND              VIA   -    MD0100PA00X+014273Y+009400X0200Y         S0      
317GND              VIA   -    MD0100PA00X+014273Y+007984X0200Y         S0      
317GND              VIA   -    M      A01X+013550Y+007044X0200Y         S2      
017GND              VIA   -    M      A06X+013550Y+007044X0260Y         S2      
017GND                    -    MD0100PA00X+013550Y+007044                       
317GND              VIA   -    MD0100PA00X+011250Y+007600X0200Y    R270 S0      
317GND              VIA   -    MD0100PA00X+012592Y+004230X0200Y         S0      
317GND              VIA   -    MD0100PA00X+012292Y+004230X0200Y         S0      
317GND              VIA   -    MD0100PA00X+012592Y+004480X0200Y         S0      
317GND              VIA   -    MD0100PA00X+012292Y+004480X0200Y         S0      
317GND              VIA   -    MD0100PA00X+012592Y+004730X0200Y         S0      
317GND              VIA   -    MD0100PA00X+012292Y+004730X0200Y         S0      
317GND              VIA   -    MD0100PA00X+012592Y+004980X0200Y         S0      
317GND              VIA   -    MD0100PA00X+012292Y+004980X0200Y         S0      
317GND              VIA   -    MD0100PA00X+008550Y+004350X0200Y         S0      
317GND              VIA   -    MD0100PA00X+008550Y+004700X0200Y         S0      
317GND              VIA   -    MD0100PA00X+007840Y+004370X0200Y         S0      
317GND              VIA   -    MD0100PA00X+007840Y+004720X0200Y         S0      
317GND              VIA   -    MD0100PA00X+011450Y+012700X0200Y         S0      
317GND              VIA   -    MD0100PA00X+007550Y+013000X0200Y    R180 S0      
317GND              VIA   -    MD0100PA00X+009106Y+009463X0200Y    R090 S0      
317GND              VIA   -    M      A01X+007165Y+011126X0200Y    R180 S2      
017GND              VIA   -    M      A06X+007165Y+011126X0260Y    R180 S2      
017GND                    -    MD0100PA00X+007165Y+011126                       
317GND              VIA   -    M      A01X+007165Y+009426X0200Y    R180 S2      
017GND              VIA   -    M      A06X+007165Y+009426X0260Y    R180 S2      
017GND                    -    MD0100PA00X+007165Y+009426                       
317GND              VIA   -    M      A01X+007517Y+007800X0200Y         S2      
017GND              VIA   -    M      A06X+007517Y+007800X0260Y         S2      
017GND                    -    MD0100PA00X+007517Y+007800                       
317GND              VIA   -    M      A01X+006910Y+007610X0200Y    R180 S2      
017GND              VIA   -    M      A06X+006910Y+007610X0260Y    R180 S2      
017GND                    -    MD0100PA00X+006910Y+007610                       
317GND              VIA   -    MD0100PA00X+006851Y+005097X0200Y    R090 S0      
317GND              VIA   -    M      A01X+006130Y+006690X0200Y    R180 S2      
017GND              VIA   -    M      A06X+006130Y+006690X0260Y    R180 S2      
017GND                    -    MD0100PA00X+006130Y+006690                       
317GND              VIA   -    MD0100PA00X+005870Y+011090X0200Y         S0      
317GND              VIA   -    MD0100PA00X+006150Y+009750X0200Y         S0      
317GND              VIA   -    MD0100PA00X+015130Y+075640X0200Y         S0      
327GND              C2031 -2          A01X+013858Y+076200X0198Y0197     S1      
327GND              C2046 -2          A01X+006342Y+077850X0198Y0197R180 S1      
327GND              D256  -A          A01X+007517Y+078361X0220Y0240R180 S1      
317GND              VIA   -    MD0100PA00X+015602Y+132377X0200Y    R090 S0      
327GND              C2021 -2          A01X+013850Y+118358X0198Y0197R090 S1      
317GND              VIA   -    M      A01X+008600Y+068800X0200Y         S2      
017GND              VIA   -    M      A06X+008600Y+068800X0260Y         S2      
017GND                    -    MD0100PA00X+008600Y+068800                       
327GND              C2127 -2          A06X+002290Y+123300X0280Y0320R270 S2      
327GND              C2120 -2          A06X+017600Y+123690X0280Y0320     S2      
327GND              C2125 -2          A01X+003700Y+039040X0280Y0320     S1      
327GND              C2122 -2          A01X+016660Y+038900X0280Y0320R090 S1      
327GND              C2126 -2          A01X+008540Y+085850X0280Y0320R270 S1      
317GND              VIA   -    MD0100PA00X+008600Y+069600X0200Y         S0      
327GND              R5686 -2          A01X+008358Y+069600X0198Y0197     S1      
327GND              R309  -2   M      A01X+007408Y+074650X0180Y0200R180 S1      
327GND              C2121 -2          A01X+018500Y+087390X0280Y0320     S1      
327GND              U407  -S          A01X+015385Y+038644X0240Y0320R270 S1      
327GND              R5656 -2   M      A01X+014850Y+039058X0198Y0197R090 S1      
327GND              C2024 -2          A01X+019200Y+087450X0400Y0500R270 S1      
317GND              VIA   -    MD0100PA00X+002350Y+123700X0200Y         S0      
317GND              VIA   -    M      A01X+006272Y+012954X0200Y    R180 S2      
017GND              VIA   -    M      A06X+006272Y+012954X0260Y    R180 S2      
017GND                    -    MD0100PA00X+006272Y+012954                       
327GND              C2096 -2          A06X+012590Y+109860X0460Y0620R180 S2      
327GND              C2097 -2          A06X+012590Y+107760X0460Y0620R180 S2      
327GND              C2098 -2          A06X+012590Y+108810X0460Y0620R180 S2      
327GND              C2099 -2          A06X+017930Y+091200X0460Y0620     S2      
327GND              C2100 -2          A06X+017930Y+092250X0460Y0620     S2      
327GND              C2101 -2          A06X+017930Y+093277X0460Y0620     S2      
327GND              C2102 -2          A06X+013260Y+034803X0460Y0620R180 S2      
327GND              C2103 -2          A06X+013260Y+036803X0460Y0620R180 S2      
327GND              C2104 -2          A06X+013260Y+035803X0460Y0620R180 S2      
327GND              C2105 -2          A06X+018180Y+019750X0460Y0620     S2      
327GND              C2106 -2          A06X+018180Y+018750X0460Y0620     S2      
327GND              C2107 -2          A06X+018170Y+020740X0460Y0620     S2      
327GND              C2108 -2          A06X+001825Y+020031X0460Y0620R180 S2      
327GND              C2109 -2          A06X+001820Y+019061X0460Y0620R180 S2      
327GND              C2110 -2          A06X+001824Y+018080X0460Y0620R180 S2      
327GND              C2111 -2          A06X+006960Y+034823X0460Y0620     S2      
327GND              C2112 -2          A06X+006960Y+035823X0460Y0620     S2      
327GND              C2113 -2          A06X+006960Y+036823X0460Y0620     S2      
327GND              C2114 -2          A06X+001623Y+092686X0460Y0620R180 S2      
327GND              C2115 -2          A06X+001623Y+090586X0460Y0620R180 S2      
327GND              C2116 -2          A06X+001623Y+091636X0460Y0620R180 S2      
327GND              C2117 -2          A06X+007187Y+109225X0460Y0620     S2      
327GND              C2118 -2          A06X+007187Y+107125X0460Y0620     S2      
327GND              C2119 -2          A06X+007187Y+108175X0460Y0620     S2      
317GND              VIA   -    MD0100PA00X+018350Y+124050X0200Y         S0      
327GND              R5647 -2          A01X+018642Y+124050X0198Y0197R180 S1      
327GND              R5669 -2          A01X+001392Y+123950X0198Y0197R180 S1      
317GND              VIA   -    MD0100PA00X+001100Y+123950X0200Y         S0      
327GND              U392  -3          A06X+001795Y+027104X0240Y0240R090 S2      
327GND              U393  -3          A06X+006361Y+027668X0240Y0240R270 S2      
327GND              C2062 -2          A01X+006656Y+027915X0198Y0197R270 S1      
317GND              VIA   -    MD0100PA00X+014950Y+085050X0200Y         S0      
327GND              U406  -S          A01X+016685Y+085344X0240Y0320R270 S1      
327GND              R5651 -2   M      A01X+016100Y+085442X0198Y0197R270 S1      
317GND              VIA   -    MD0100PA00X+009900Y+085300X0200Y         S0      
327GND              U411  -S   M      A01X+008715Y+085106X0240Y0320R090 S1      
327GND              R5668 -2   M      A01X+009250Y+084908X0198Y0197R090 S1      
327GND              R5426 -2   M      A06X+016258Y+053000X0180Y0200     S2      
327GND              R5428 -2   M      A06X+016258Y+052550X0180Y0200     S2      
327GND              R5427 -2   M      A06X+016258Y+052100X0180Y0200     S2      
327GND              R5429 -2   M      A06X+016258Y+051650X0180Y0200     S2      
327GND              R5430 -2   M      A06X+016258Y+051200X0180Y0200     S2      
327GND              R5431 -2   M      A06X+016258Y+050300X0180Y0200     S2      
327GND              R5432 -2   M      A06X+016258Y+050750X0180Y0200     S2      
327GND              R5433 -2          A06X+016258Y+049850X0180Y0200     S2      
327GND              R5434 -2          A06X+007108Y+049700X0180Y0200     S2      
327GND              R5435 -2   M      A06X+007108Y+050600X0180Y0200     S2      
327GND              R5436 -2   M      A06X+007108Y+050150X0180Y0200     S2      
327GND              R5437 -2   M      A06X+007108Y+051050X0180Y0200     S2      
327GND              R5438 -2   M      A06X+007108Y+051500X0180Y0200     S2      
327GND              R5439 -2   M      A06X+007108Y+052400X0180Y0200     S2      
327GND              R5440 -2   M      A06X+007108Y+051950X0180Y0200     S2      
327GND              R5441 -2   M      A06X+007108Y+052850X0180Y0200     S2      
327GND              R5673 -2          A01X+008358Y+067200X0198Y0197     S1      
317GND              VIA   -    M      A01X+008600Y+068000X0200Y         S2      
017GND              VIA   -    M      A06X+008600Y+068000X0260Y         S2      
017GND                    -    MD0100PA00X+008600Y+068000                       
327GND              R5674 -2          A01X+008358Y+068000X0198Y0197     S1      
327GND              C1938 -1          A01X+008750Y+048392X0198Y0197R090 S1      
327GND              C2095 -1          A01X+001342Y+052000X0198Y0197     S1      
327GND              PR6   -2          A06X+018550Y+101642X0198Y0197R090 S2      
327GND              PR10  -1   M      A06X+018150Y+101642X0198Y0197R270 S2      
327GND              PR30  -2          A06X+012650Y+098676X0198Y0197R270 S2      
327GND              PR34  -1   M      A06X+013050Y+098676X0198Y0197R090 S2      
327GND              PR38  -2          A06X+018700Y+028965X0198Y0197R090 S2      
327GND              PR42  -1   M      A06X+018300Y+028965X0198Y0197R270 S2      
327GND              C2080 -2   M      A01X+009892Y+071100X0198Y0197R180 S1      
327GND              C2081 -2          A01X+009892Y+070650X0198Y0197R180 S1      
327GND              C2085 -2   M      A01X+009542Y+073100X0198Y0197R180 S1      
327GND              C2086 -2          A01X+018758Y+073300X0198Y0197     S1      
327GND              PR26  -2          A06X+012748Y+025680X0198Y0197R270 S2      
327GND              PR46  -1   M      A06X+013150Y+025684X0198Y0197R090 S2      
327GND              PR50  -2          A06X+000700Y+025680X0198Y0197R270 S2      
327GND              PR54  -1   M      A06X+001100Y+025684X0198Y0197R090 S2      
327GND              PR66  -2          A06X+000650Y+098358X0198Y0197R270 S2      
327GND              PR70  -1   M      A06X+001050Y+098358X0198Y0197R090 S2      
327GND              PR74  -2          A06X+007656Y+101642X0198Y0197R090 S2      
327GND              PR78  -1   M      A06X+007256Y+101642X0198Y0197R270 S2      
327GND              C2022 -2          A01X+012842Y+118350X0198Y0197R180 S1      
327GND              D268  -A   M      A01X+012833Y+117850X0220Y0240     S1      
317GND              VIA   -    MD0100PA00X+012544Y+117597X0200Y         S0      
327GND              PC49  -2          A06X+001646Y+093590X0400Y0500R180 S2      
327GND              PC37  -2          A06X+001835Y+020891X0400Y0500R180 S2      
327GND              PC36  -2          A06X+017940Y+021590X0400Y0500     S2      
327GND              PC30  -2          A06X+013400Y+033900X0400Y0500R180 S2      
327GND              PC43  -2          A06X+006950Y+033930X0400Y0500     S2      
327GND              PC24  -2          A06X+017918Y+094160X0400Y0500     S2      
327GND              PC55  -2          A06X+007165Y+106269X0400Y0500     S2      
327GND              PC1   -2          A06X+013100Y+106900X0400Y0500R180 S2      
327GND              C157  -2          A01X+001470Y+014453X0400Y0500R270 S1      
327GND              C2048 -2          A01X+018905Y+014563X0400Y0500R270 S1      
327GND              C2038 -2          A01X+001860Y+086700X0400Y0500R270 S1      
327GND              C2018 -2          A01X+019150Y+122100X0400Y0500R180 S1      
327GND              C2050 -2          A01X+001200Y+122100X0400Y0500     S1      
317GND              VIA   -    MD0100PA00X+018274Y+123515X0200Y         S0      
327GND              U405  -S          A01X+018544Y+123515X0240Y0320R180 S1      
317GND              VIA   -    MD0100PA00X+014133Y+039800X0200Y         S0      
327GND              D277  -A          A01X+014133Y+040073X0220Y0240     S1      
317GND              VIA   -    MD0100PA00X+001024Y+123415X0200Y         S0      
327GND              U412  -S          A01X+001294Y+123415X0240Y0320R180 S1      
327GND              C100  -2          A01X+008550Y+119658X0198Y0197R090 S1      
317GND              VIA   -    MD0100PA00X+005600Y+120327X0200Y         S0      
327GND              D259  -A          A01X+005600Y+120067X0220Y0240R270 S1      
317GND              H1    -1   MD1190PA00X+010177Y+020437X3550Y8270     S3      
317GND              H2    -1   MD1190PA00X+010177Y+095240X3550Y8270     S3      
317GND              H11   -1   M      A01X+010177Y+128705X4000Y         S3      
017GND              H11   -1   M      A06X+010177Y+128705X3940Y         S3      
017GND                    -    MD2520PA00X+010177Y+128705                       
327GND              PR58  -2          A06X+007706Y+028965X0180Y0200R270 S2      
327GND              PR62  -1   M      A06X+007256Y+028965X0180Y0200R090 S2      
317GND              VIA   -    MD0100PA00X+011556Y+075906X0200Y         S0      
327GND              C2092 -2          A01X+011750Y+076542X0198Y0197R270 S1      
317GND              VIA   -    MD0100PA00X+012438Y+040931X0200Y         S0      
327GND              C2043 -2          A01X+012942Y+040800X0198Y0197R180 S1      
317GND              VIA   -    M      A01X+011350Y+047600X0200Y         S2      
017GND              VIA   -    M      A06X+011350Y+047600X0260Y         S2      
017GND                    -    MD0100PA00X+011350Y+047600                       
327GND              R4936 -1   M      A01X+011900Y+047842X0198Y0197R090 S1      
327GND              R4940 -1   M      A01X+011350Y+047842X0198Y0197R090 S1      
327GND              R4782 -1   M      A01X+012450Y+047842X0198Y0197R090 S1      
327GND              R4781 -1   M      A01X+013000Y+047842X0198Y0197R090 S1      
327GND              R4935 -1          A01X+013550Y+047842X0198Y0197R090 S1      
317GND              VIA   -    M      A01X+008650Y+048150X0200Y         S2      
017GND              VIA   -    M      A06X+008650Y+048150X0260Y         S2      
017GND                    -    MD0100PA00X+008650Y+048150                       
317GND              VIA   -    MD0100PA00X+010573Y+049684X0200Y         S0      
327GND              R4954 -1          A01X+010208Y+049850X0198Y0197R180 S1      
317GND              VIA   -    MD0100PA00X+010582Y+048850X0200Y         S0      
327GND              R4953 -1          A01X+010208Y+048850X0198Y0197R180 S1      
317GND              VIA   -    MD0100PA00X+006850Y+053708X0200Y         S0      
327GND              R4952 -1          A01X+009300Y+053708X0198Y0197R270 S1      
327GND              R4951 -1   M      A01X+008750Y+053708X0198Y0197R270 S1      
327GND              R4851 -1   M      A01X+008200Y+053708X0198Y0197R270 S1      
327GND              R4950 -1   M      A01X+007100Y+053708X0198Y0197R270 S1      
327GND              R4850 -1   M      A01X+007650Y+053708X0198Y0197R270 S1      
317GND              VIA   -    MD0100PA00X+009892Y+051250X0200Y         S0      
327GND              R4944 -1          A01X+009892Y+050950X0198Y0197     S1      
317GND              VIA   -    MD0100PA00X+009892Y+052400X0200Y         S0      
327GND              R4942 -1          A01X+009892Y+052150X0198Y0197     S1      
327GND              D278  -A          A01X+014133Y+045673X0220Y0240     S1      
317GND              VIA   -    M      A01X+007450Y+047500X0200Y         S2      
017GND              VIA   -    M      A06X+007450Y+047500X0260Y         S2      
017GND                    -    MD0100PA00X+007450Y+047500                       
327GND              C2035 -2          A01X+007208Y+047500X0198Y0197     S1      
317GND              VIA   -    MD0100PA00X+006555Y+064550X0200Y         S0      
327GND              C54   -2          A01X+006308Y+064700X0198Y0197     S1      
327GND              C52   -2          A01X+006308Y+064100X0198Y0197     S1      
327GND              U362  -S          A01X+007165Y+045406X0240Y0320R090 S1      
317GND              VIA   -    MD0100PA00X+009300Y+073100X0200Y         S0      
317GND              VIA   -    MD0100PA00X+006640Y+065540X0200Y         S0      
327GND              C58   -2          A01X+006308Y+066000X0198Y0197     S1      
327GND              C56   -2   M      A01X+006308Y+065540X0198Y0197     S1      
317GND              VIA   -    M      A01X+008330Y+062410X0200Y         S2      
017GND              VIA   -    M      A06X+008330Y+062410X0260Y         S2      
017GND                    -    MD0100PA00X+008330Y+062410                       
327GND              R5470 -2          A01X+008090Y+062842X0198Y0197R270 S1      
327GND              D267  -A          A01X+012783Y+119800X0220Y0240     S1      
317GND              VIA   -    MD0100PA00X+001100Y+050650X0200Y         S0      
327GND              R5572 -1          A01X+001342Y+050650X0198Y0197     S1      
317GND              VIA   -    MD0100PA00X+001100Y+051550X0200Y         S0      
327GND              R5571 -1          A01X+001342Y+051550X0198Y0197     S1      
317GND              VIA   -    MD0100PA00X+001100Y+052000X0200Y         S0      
317GND              VIA   -    MD0100PA00X+003548Y+053408X0200Y         S0      
327GND              R5570 -1          A01X+003300Y+053408X0198Y0197R270 S1      
317GND              VIA   -    MD0100PA00X+003750Y+051250X0200Y    R090 S0      
317GND              VIA   -    MD0100PA00X+003750Y+052050X0200Y    R090 S0      
317GND              VIA   -    MD0100PA00X+002950Y+051250X0200Y    R090 S0      
317GND              VIA   -    MD0100PA00X+002950Y+052050X0200Y    R090 S0      
327GND              U404  -TH  M      A01X+003350Y+051650X1090Y1090R090 S1      
317GND              VIA   -    MD0100PA00X+004925Y+051675X0200Y         S0      
327GND              U404  -9          A01X+004157Y+051552X0110Y0360R090 S1      
327GND              C2026 -2          A01X+001700Y+049650X0400Y0500R180 S1      
317GND              VIA   -    MD0100PA00X+007463Y+051508X0200Y         S0      
327GND              U330  -8          A01X+007463Y+051322X0070Y0320R270 S1      
317GND              VIA   -    MD0100PA00X+008650Y+050450X0200Y    R090 S0      
317GND              VIA   -    MD0100PA00X+007850Y+050450X0200Y    R090 S0      
317GND              VIA   -    MD0100PA00X+008650Y+051250X0200Y    R090 S0      
317GND              VIA   -    MD0100PA00X+007850Y+051250X0200Y    R090 S0      
327GND              U330  -TH  M      A01X+008250Y+050850X1070Y1070     S1      
317GND              VIA   -    MD0100PA00X+019158Y+051850X0200Y         S0      
327GND              R5560 -1          A01X+019158Y+052100X0198Y0197R180 S1      
317GND              VIA   -    MD0100PA00X+017900Y+053508X0200Y         S0      
327GND              C2094 -1          A01X+017650Y+053508X0198Y0197R270 S1      
317GND              VIA   -    MD0100PA00X+016900Y+054208X0200Y         S0      
327GND              R5564 -1          A01X+016650Y+054208X0198Y0197R270 S1      
327GND              R5563 -1          A01X+017150Y+054208X0198Y0197R270 S1      
317GND              VIA   -    MD0100PA00X+011600Y+052950X0200Y         S0      
327GND              C1932 -1          A01X+011600Y+052708X0198Y0197R270 S1      
327GND              U317  -8          A01X+013187Y+050378X0070Y0320R090 S1      
317GND              VIA   -    MD0100PA00X+013400Y+050100X0200Y         S0      
317GND              VIA   -    MD0100PA00X+017700Y+051400X0200Y    R090 S0      
317GND              VIA   -    MD0100PA00X+016900Y+051400X0200Y    R090 S0      
317GND              VIA   -    MD0100PA00X+017700Y+052200X0200Y    R090 S0      
327GND              U403  -TH  M      A01X+017300Y+051800X1090Y1090     S1      
317GND              VIA   -    MD0100PA00X+016900Y+052200X0200Y    R090 S0      
317GND              VIA   -    MD0100PA00X+017000Y+050450X0200Y         S0      
327GND              U403  -9          A01X+017202Y+050993X0110Y0360     S1      
317GND              VIA   -    MD0100PA00X+012800Y+050450X0200Y    R090 S0      
317GND              VIA   -    MD0100PA00X+012000Y+050450X0200Y    R090 S0      
317GND              VIA   -    MD0100PA00X+012000Y+051250X0200Y    R090 S0      
317GND              VIA   -    MD0100PA00X+012800Y+051250X0200Y    R090 S0      
327GND              U317  -TH  M      A01X+012400Y+050850X1070Y1070R180 S1      
327GND              PC60  -2          A06X+016436Y+024123X0400Y0500R090 S2      
327GND              PC62  -2          A06X+003868Y+030523X0400Y0500R270 S2      
327GND              PC9   -2          A06X+016626Y+097265X0400Y0500R090 S2      
327GND              PC63  -2          A06X+004087Y+096930X0400Y0500R090 S2      
327GND              PC64  -2          A06X+003906Y+103067X0400Y0500R270 S2      
327GND              PC3124-1   M      A06X+002608Y+098450X0198Y0197     S2      
327GND              PC3125-1   M      A06X+005650Y+101642X0198Y0197R270 S2      
327GND              PC3118-1   M      A06X+016950Y+101642X0198Y0197R270 S2      
327GND              PC3119-1   M      A06X+014650Y+098676X0198Y0197R090 S2      
327GND              PC3120-1   M      A06X+016700Y+028965X0198Y0197R270 S2      
327GND              PC3123-1   M      A06X+005550Y+028965X0198Y0197R270 S2      
327GND              PC3122-1   M      A06X+002608Y+025750X0198Y0197     S2      
327GND              PC3121-1   M      A06X+014750Y+025684X0198Y0197R090 S2      
327GND              D280  -A   M      A01X+012783Y+045161X0220Y0240     S1      
327GND              D279  -A          A01X+012833Y+047073X0220Y0240     S1      
317GND              VIA   -    MD0100PA00X+001358Y+019864X0200Y    R270 S0      
317GND              VIA   -    MD0100PA00X+001358Y+020164X0200Y    R270 S0      
317GND              VIA   -    MD0100PA00X+005217Y+025633X0200Y    R180 S0      
317GND              VIA   -    MD0100PA00X+005517Y+025633X0200Y    R180 S0      
317GND              VIA   -    MD0100PA00X+006117Y+025633X0200Y    R180 S0      
317GND              VIA   -    MD0100PA00X+005817Y+025633X0200Y    R180 S0      
317GND              VIA   -    MD0100PA00X+018676Y+020574X0200Y    R090 S0      
317GND              VIA   -    MD0100PA00X+018676Y+020874X0200Y    R090 S0      
317GND              VIA   -    MD0100PA00X+018697Y+025373X0200Y    R180 S0      
317GND              VIA   -    MD0100PA00X+018397Y+025373X0200Y    R180 S0      
317GND              VIA   -    MD0100PA00X+017797Y+025373X0200Y    R180 S0      
317GND              VIA   -    MD0100PA00X+018097Y+025373X0200Y    R180 S0      
317GND              VIA   -    MD0100PA00X+012790Y+036790X0200Y         S0      
317GND              VIA   -    MD0100PA00X+013020Y+033740X0200Y    R270 S0      
317GND              VIA   -    MD0100PA00X+013020Y+033990X0200Y    R270 S0      
317GND              VIA   -    MD0100PA00X+007330Y+033810X0200Y    R270 S0      
317GND              VIA   -    MD0100PA00X+007330Y+034060X0200Y    R270 S0      
317GND              VIA   -    MD0100PA00X+001566Y+087332X0200Y    R090 S0      
317GND              VIA   -    MD0100PA00X+001566Y+087632X0200Y    R090 S0      
317GND              VIA   -    MD0100PA00X+001566Y+087932X0200Y    R090 S0      
317GND              VIA   -    MD0100PA00X+001560Y+087060X0200Y    R090 S0      
317GND              VIA   -    MD0100PA00X+001280Y+087060X0200Y    R090 S0      
317GND              VIA   -    MD0100PA00X+001286Y+087932X0200Y    R090 S0      
317GND              VIA   -    MD0100PA00X+001286Y+087632X0200Y    R090 S0      
317GND              VIA   -    MD0100PA00X+001286Y+087332X0200Y    R090 S0      
317GND              VIA   -    MD0100PA00X+004866Y+099412X0200Y    R090 S0      
317GND              VIA   -    MD0100PA00X+004866Y+099112X0200Y    R090 S0      
317GND              VIA   -    MD0100PA00X+004866Y+098812X0200Y    R090 S0      
317GND              VIA   -    MD0100PA00X+004866Y+098512X0200Y    R090 S0      
317GND              VIA   -    MD0100PA00X+005116Y+098512X0200Y    R090 S0      
317GND              VIA   -    MD0100PA00X+005116Y+098812X0200Y    R090 S0      
317GND              VIA   -    MD0100PA00X+005116Y+099112X0200Y    R090 S0      
317GND              VIA   -    MD0100PA00X+005116Y+099412X0200Y    R090 S0      
317GND              VIA   -    MD0100PA00X+018026Y+088992X0200Y    R090 S0      
317GND              VIA   -    MD0100PA00X+018026Y+089292X0200Y    R090 S0      
317GND              VIA   -    MD0100PA00X+018026Y+089592X0200Y    R090 S0      
317GND              VIA   -    MD0100PA00X+018026Y+089892X0200Y    R090 S0      
317GND              VIA   -    MD0100PA00X+018528Y+098220X0200Y         S0      
317GND              VIA   -    MD0100PA00X+018828Y+098220X0200Y         S0      
317GND              VIA   -    MD0100PA00X+017928Y+098220X0200Y         S0      
317GND              VIA   -    MD0100PA00X+018228Y+098220X0200Y         S0      
317GND              VIA   -    MD0100PA00X+012679Y+106784X0200Y    R270 S0      
317GND              VIA   -    MD0100PA00X+012676Y+107102X0200Y    R270 S0      
317GND              VIA   -    MD0100PA00X+019036Y+106006X0200Y         S0      
317GND              VIA   -    MD0100PA00X+018736Y+106006X0200Y         S0      
317GND              VIA   -    MD0100PA00X+018436Y+106006X0200Y         S0      
317GND              VIA   -    MD0100PA00X+018136Y+106006X0200Y         S0      
317GND              VIA   -    MD0100PA00X+017807Y+025653X0200Y    R180 S0      
317GND              VIA   -    MD0100PA00X+018707Y+025653X0200Y    R180 S0      
317GND              VIA   -    MD0100PA00X+018407Y+025653X0200Y    R180 S0      
317GND              VIA   -    MD0100PA00X+018107Y+025653X0200Y    R180 S0      
317GND              VIA   -    MD0100PA00X+019016Y+099800X0200Y    R180 S0      
317GND              VIA   -    MD0100PA00X+019016Y+099500X0200Y    R180 S0      
317GND              VIA   -    MD0100PA00X+012107Y+109700X0200Y    R270 S0      
327GND              PR51  -2          A01X+002242Y+025150X0198Y0197R180 S1      
327GND              PR53  -2   M      A06X+002608Y+025350X0198Y0197R180 S2      
327GND              PR59  -2          A01X+005258Y+029300X0198Y0197     S1      
327GND              PR61  -2   M      A06X+005950Y+028965X0198Y0197R090 S2      
327GND              PC47  -2   M      A06X+006350Y+028965X0198Y0197R090 S2      
327GND              PC46  -2   M      A06X+006806Y+028965X0198Y0197R090 S2      
327GND              PC44  -2   M      A06X+004900Y+028962X0198Y0197R090 S2      
327GND              PC45  -2   M      A06X+004512Y+028962X0198Y0197R090 S2      
327GND              PC2123-2          A06X+003706Y+028962X0198Y0197R090 S2      
327GND              PR60  -2   M      A06X+004112Y+028962X0198Y0197R090 S2      
327GND              PR39  -2          A01X+016208Y+029200X0198Y0197     S1      
327GND              PR41  -2   M      A06X+017100Y+028965X0198Y0197R090 S2      
327GND              PC34  -2   M      A06X+017500Y+028965X0198Y0197R090 S2      
327GND              PC33  -2   M      A06X+017900Y+028965X0198Y0197R090 S2      
327GND              PC31  -2   M      A06X+016050Y+028965X0198Y0197R090 S2      
327GND              PC32  -2   M      A06X+015642Y+028962X0198Y0197R090 S2      
327GND              PC2120-2          A06X+014850Y+028962X0198Y0197R090 S2      
327GND              PR40  -2   M      A06X+015242Y+028962X0198Y0197R090 S2      
327GND              PR43  -2          A01X+014608Y+024900X0198Y0197     S1      
327GND              PC19  -2   M      A06X+015842Y+025684X0198Y0197R270 S2      
327GND              PC18  -2   M      A06X+015400Y+025684X0198Y0197R270 S2      
327GND              PR44  -2   M      A06X+016242Y+025684X0198Y0197R270 S2      
327GND              PC2121-2          A06X+016642Y+025684X0198Y0197R270 S2      
327GND              PC20  -2   M      A06X+013550Y+025684X0198Y0197R270 S2      
327GND              PC21  -2   M      A06X+013950Y+025684X0198Y0197R270 S2      
327GND              PR45  -2   M      A06X+014350Y+025684X0198Y0197R270 S2      
327GND              PR67  -2          A01X+002508Y+098150X0198Y0197     S1      
327GND              C2071 -2          A01X+001279Y+099408X0198Y0197R090 S1      
327GND              PC2124-2          A06X+004250Y+098358X0198Y0197R270 S2      
327GND              PR68  -2   M      A06X+003850Y+098358X0198Y0197R270 S2      
327GND              PC51  -2   M      A06X+003450Y+098358X0198Y0197R270 S2      
327GND              PC50  -2   M      A06X+003050Y+098358X0198Y0197R270 S2      
327GND              PR31  -2          A01X+014758Y+098050X0198Y0197     S1      
327GND              PC2119-2          A06X+016600Y+098676X0198Y0197R270 S2      
327GND              PR32  -2   M      A06X+016192Y+098676X0198Y0197R270 S2      
327GND              PC26  -2   M      A06X+015792Y+098676X0198Y0197R270 S2      
327GND              PC25  -2   M      A06X+015350Y+098676X0198Y0197R270 S2      
327GND              PR33  -2   M      A06X+014250Y+098676X0198Y0197R270 S2      
327GND              PC28  -2   M      A06X+013850Y+098676X0198Y0197R270 S2      
327GND              PC27  -2   M      A06X+013450Y+098676X0198Y0197R270 S2      
327GND              PR75  -2          A01X+005642Y+102400X0198Y0197R180 S1      
327GND              PR7   -2          A01X+016492Y+102550X0198Y0197R180 S1      
327GND              PR9   -2   M      A06X+016550Y+101642X0198Y0197R090 S2      
327GND              PC6   -2   M      A06X+017350Y+101642X0198Y0197R090 S2      
327GND              PC5   -2   M      A06X+017750Y+101642X0198Y0197R090 S2      
327GND              PU1   -25         A06X+016463Y+103171X0070Y0360R180 S2      
317GND              VIA   -    MD0100PA00X+016250Y+102300X0200Y         S0      
327GND              PU4   -25         A06X+014771Y+097144X0070Y0360     S2      
317GND              VIA   -    MD0100PA00X+015100Y+098100X0200Y    R180 S0      
327GND              PU5   -25         A06X+016463Y+030494X0070Y0360R180 S2      
317GND              VIA   -    MD0100PA00X+016430Y+029772X0200Y         S0      
327GND              PU3   -25         A06X+014771Y+024152X0070Y0360     S2      
317GND              VIA   -    MD0100PA00X+014900Y+025000X0200Y    R180 S0      
327GND              PU6   -25         A06X+002402Y+024152X0070Y0360     S2      
317GND              VIA   -    MD0100PA00X+002554Y+024858X0200Y    R180 S0      
327GND              PU7   -25         A06X+005534Y+030494X0070Y0360R180 S2      
317GND              VIA   -    MD0100PA00X+005493Y+029665X0200Y         S0      
327GND              PU8   -25         A06X+002402Y+096829X0070Y0360     S2      
317GND              VIA   -    MD0100PA00X+002550Y+097750X0200Y    R180 S0      
327GND              PU9   -25         A06X+005584Y+103171X0070Y0360R180 S2      
317GND              VIA   -    MD0100PA00X+005300Y+102150X0200Y         S0      
317GND              VIA   -    MD0100PA00X+007589Y+106114X0200Y    R270 S0      
317GND              VIA   -    MD0100PA00X+007586Y+106432X0200Y    R270 S0      
317GND              VIA   -    MD0100PA00X+007653Y+106961X0200Y    R270 S0      
317GND              VIA   -    MD0100PA00X+007646Y+107295X0200Y    R270 S0      
317GND              VIA   -    MD0100PA00X+007646Y+107918X0200Y    R270 S0      
317GND              VIA   -    MD0100PA00X+007653Y+107584X0200Y    R270 S0      
317GND              VIA   -    MD0100PA00X+004056Y+102717X0200Y         S0      
317GND              VIA   -    MD0100PA00X+003756Y+102717X0200Y         S0      
327GND              PD18  -A          A06X+002168Y+102251X0950Y1300R270 S2      
317GND              VIA   -    MD0100PA00X+002298Y+101280X0200Y         S0      
317GND              VIA   -    MD0100PA00X+002598Y+101280X0200Y         S0      
317GND              VIA   -    MD0100PA00X+002298Y+101580X0200Y         S0      
317GND              VIA   -    MD0100PA00X+002598Y+101580X0200Y         S0      
317GND              VIA   -    MD0100PA00X+002598Y+102880X0200Y         S0      
317GND              VIA   -    MD0100PA00X+002298Y+102880X0200Y         S0      
317GND              VIA   -    MD0100PA00X+001698Y+101280X0200Y         S0      
317GND              VIA   -    MD0100PA00X+001998Y+101280X0200Y         S0      
317GND              VIA   -    MD0100PA00X+001698Y+101580X0200Y         S0      
317GND              VIA   -    MD0100PA00X+001998Y+101580X0200Y         S0      
317GND              VIA   -    MD0100PA00X+001998Y+102880X0200Y         S0      
317GND              VIA   -    MD0100PA00X+001698Y+102880X0200Y         S0      
317GND              VIA   -    MD0100PA00X+004800Y+101204X0200Y         S0      
327GND              C2073 -2          A01X+004714Y+100950X0198Y0197     S1      
317GND              VIA   -    MD0100PA00X+005624Y+100400X0200Y         S0      
327GND              U385  -3          A06X+005235Y+100494X0130Y0460R090 S2      
317GND              VIA   -    MD0100PA00X+006411Y+100650X0200Y         S0      
327GND              U398  -3          A06X+006411Y+100346X0240Y0240R270 S2      
327GND              C2072 -2          A01X+006706Y+100592X0198Y0197R270 S1      
327GND              PD4   -A          A06X+018380Y+098869X0950Y1300R090 S2      
317GND              VIA   -    MD0100PA00X+018166Y+099800X0200Y    R180 S0      
317GND              VIA   -    MD0100PA00X+018166Y+099500X0200Y    R180 S0      
317GND              VIA   -    MD0100PA00X+018466Y+099800X0200Y    R180 S0      
317GND              VIA   -    MD0100PA00X+018466Y+099500X0200Y    R180 S0      
317GND              VIA   -    MD0100PA00X+018766Y+099800X0200Y    R180 S0      
317GND              VIA   -    MD0100PA00X+018766Y+099500X0200Y    R180 S0      
317GND              VIA   -    MD0100PA00X+016776Y+097650X0200Y    R180 S0      
317GND              VIA   -    MD0100PA00X+016476Y+097650X0200Y    R180 S0      
327GND              PC29  -2          A01X+012138Y+035810X0870Y1740R270 S1      
317GND              VIA   -    MD0100PA00X+003718Y+030173X0200Y         S0      
317GND              VIA   -    MD0100PA00X+004018Y+030173X0200Y         S0      
317GND              VIA   -    MD0100PA00X+004756Y+028023X0200Y         S0      
327GND              C2063 -2          A01X+004664Y+028273X0198Y0197     S1      
327GND              PD16  -A          A06X+002118Y+029574X0950Y1300R270 S2      
317GND              VIA   -    MD0100PA00X+001818Y+028923X0200Y         S0      
317GND              VIA   -    M      A01X+001818Y+028623X0200Y         S2      
017GND              VIA   -    M      A06X+001818Y+028623X0260Y         S2      
017GND                    -    MD0100PA00X+001818Y+028623                       
317GND              VIA   -    MD0100PA00X+002418Y+028923X0200Y         S0      
317GND              VIA   -    MD0100PA00X+002118Y+028923X0200Y         S0      
317GND              VIA   -    MD0100PA00X+002718Y+028923X0200Y         S0      
317GND              VIA   -    MD0100PA00X+002418Y+028623X0200Y         S0      
317GND              VIA   -    MD0100PA00X+002118Y+028623X0200Y         S0      
317GND              VIA   -    M      A01X+002718Y+028623X0200Y         S2      
017GND              VIA   -    M      A06X+002718Y+028623X0260Y         S2      
017GND                    -    MD0100PA00X+002718Y+028623                       
317GND              VIA   -    MD0100PA00X+005673Y+027817X0200Y         S0      
327GND              U361  -3          A06X+005185Y+027817X0130Y0460R090 S2      
317GND              VIA   -    MD0100PA00X+018358Y+021423X0200Y    R180 S0      
317GND              VIA   -    MD0100PA00X+018358Y+021723X0200Y    R180 S0      
317GND              VIA   -    MD0100PA00X+016286Y+024473X0200Y    R180 S0      
317GND              VIA   -    MD0100PA00X+016586Y+024473X0200Y    R180 S0      
327GND              PD14  -A          A06X+018296Y+026312X0950Y1300R090 S2      
317GND              VIA   -    MD0100PA00X+017826Y+026953X0200Y    R180 S0      
317GND              VIA   -    MD0100PA00X+018726Y+026953X0200Y    R180 S0      
317GND              VIA   -    MD0100PA00X+018426Y+026953X0200Y    R180 S0      
317GND              VIA   -    MD0100PA00X+018126Y+026953X0200Y    R180 S0      
317GND              VIA   -    MD0100PA00X+015548Y+026623X0200Y    R180 S0      
327GND              C172  -2          A01X+015641Y+026373X0198Y0197R180 S1      
317GND              VIA   -    MD0100PA00X+014598Y+026829X0200Y    R180 S0      
327GND              U74   -3          A06X+015119Y+026829X0130Y0460R270 S2      
317GND              VIA   -    MD0100PA00X+013944Y+026673X0200Y    R180 S0      
327GND              U391  -3          A06X+013944Y+026977X0240Y0240R090 S2      
327GND              C165  -2          A01X+013648Y+026730X0198Y0197R090 S1      
327GND              PD7   -A          A06X+001546Y+016293X0990Y1300     S2      
317GND              VIA   -    MD0100PA00X+001308Y+018984X0200Y    R270 S0      
317GND              VIA   -    MD0100PA00X+001308Y+019284X0200Y    R270 S0      
317GND              VIA   -    MD0100PA00X+001308Y+017934X0200Y    R270 S0      
317GND              VIA   -    MD0100PA00X+001308Y+018234X0200Y    R270 S0      
317GND              VIA   -    MD0100PA00X+001121Y+017094X0200Y    R090 S0      
317GND              VIA   -    MD0100PA00X+001121Y+017394X0200Y    R090 S0      
317GND              VIA   -    MD0100PA00X+001187Y+015489X0200Y    R090 S0      
317GND              VIA   -    MD0100PA00X+000891Y+016024X0200Y    R090 S0      
317GND              VIA   -    MD0100PA00X+000891Y+016324X0200Y    R090 S0      
317GND              VIA   -    MD0100PA00X+001371Y+017094X0200Y    R090 S0      
327GND              PC22  -2          A01X+002278Y+015513X0870Y1740R270 S1      
317GND              VIA   -    MD0100PA00X+001371Y+017394X0200Y    R090 S0      
317GND              VIA   -    MD0100PA00X+018696Y+019654X0200Y    R090 S0      
317GND              VIA   -    MD0100PA00X+018696Y+019954X0200Y    R090 S0      
317GND              VIA   -    MD0100PA00X+018696Y+018604X0200Y    R090 S0      
317GND              VIA   -    MD0100PA00X+018696Y+018904X0200Y    R090 S0      
327GND              PC35  -2          A01X+018067Y+015513X0870Y1740R090 S1      
317GND              VIA   -    MD0100PA00X+007470Y+034850X0200Y    R270 S0      
317GND              VIA   -    MD0100PA00X+007443Y+036550X0200Y    R270 S0      
317GND              VIA   -    MD0100PA00X+007443Y+036800X0200Y    R270 S0      
317GND              VIA   -    MD0100PA00X+007470Y+035100X0200Y    R270 S0      
317GND              VIA   -    MD0100PA00X+007443Y+037050X0200Y    R270 S0      
327GND              PC42  -2          A01X+008106Y+035830X0870Y1740R090 S1      
317GND              VIA   -    MD0100PA00X+007470Y+034600X0200Y    R270 S0      
317GND              VIA   -    MD0100PA00X+012790Y+035180X0200Y         S0      
317GND              VIA   -    MD0100PA00X+012780Y+037090X0200Y         S0      
317GND              VIA   -    MD0100PA00X+012790Y+036430X0200Y         S0      
317GND              VIA   -    MD0100PA00X+012790Y+034510X0200Y         S0      
317GND              VIA   -    MD0100PA00X+012800Y+034830X0200Y         S0      
317GND              VIA   -    MD0100PA00X+001170Y+092575X0200Y    R180 S0      
317GND              VIA   -    MD0100PA00X+001170Y+092875X0200Y    R180 S0      
317GND              VIA   -    MD0100PA00X+001170Y+091575X0200Y    R180 S0      
317GND              VIA   -    MD0100PA00X+001170Y+091875X0200Y    R180 S0      
317GND              VIA   -    MD0100PA00X+001170Y+090475X0200Y    R180 S0      
317GND              VIA   -    MD0100PA00X+001170Y+090775X0200Y    R180 S0      
327GND              PC48  -2          A01X+002748Y+088000X0870Y1740R270 S1      
327GND              PC23  -2          A01X+017692Y+088340X0870Y1740R090 S1      
317GND              VIA   -    MD0100PA00X+018438Y+091350X0200Y    R180 S0      
317GND              VIA   -    MD0100PA00X+018438Y+091050X0200Y    R180 S0      
317GND              VIA   -    MD0100PA00X+018438Y+092450X0200Y    R180 S0      
317GND              VIA   -    MD0100PA00X+018438Y+092150X0200Y    R180 S0      
317GND              VIA   -    MD0100PA00X+018438Y+093450X0200Y    R180 S0      
317GND              VIA   -    MD0100PA00X+018438Y+093150X0200Y    R180 S0      
327GND              PC54  -2          A01X+008106Y+108507X0870Y1740R090 S1      
317GND              VIA   -    MD0100PA00X+007649Y+109123X0200Y    R270 S0      
317GND              VIA   -    MD0100PA00X+007643Y+109456X0200Y    R270 S0      
327GND              PC7   -2          A01X+011998Y+108507X0870Y1740R270 S1      
317GND              VIA   -    MD0100PA00X+012107Y+107250X0200Y    R270 S0      
317GND              VIA   -    MD0100PA00X+012107Y+107500X0200Y    R270 S0      
317GND              VIA   -    MD0100PA00X+012107Y+107750X0200Y    R270 S0      
317GND              VIA   -    MD0100PA00X+012107Y+109200X0200Y    R270 S0      
317GND              VIA   -    MD0100PA00X+012107Y+109450X0200Y    R270 S0      
327GND              PD3   -A          A06X+013048Y+102251X0950Y1300R270 S2      
327GND              PD6   -A          A06X+013048Y+029574X0950Y1300R270 S2      
327GND              PD15  -A          A06X+005817Y+026572X0950Y1300R090 S2      
327GND              PD17  -A          A06X+005937Y+098989X0950Y1300R090 S2      
327GND              C51   -2   M      A06X+004064Y+065652X0198Y0197R180 S2      
327GND              C53   -2   M      A06X+004064Y+066052X0198Y0197R180 S2      
327GND              C57   -2   M      A06X+004058Y+066450X0198Y0197R180 S2      
327GND              C55   -2   M      A06X+004058Y+066850X0198Y0197R180 S2      
317GND              J8    -9   MD0380PA00X+002638Y+117051X0540Y    R270 S3      
317GND              J8    -8   MD0380PA00X+003425Y+116264X0540Y    R270 S3      
317GND              J7    -9   MD0380PA00X+002638Y+080713X0540Y    R270 S3      
317GND              J7    -8   MD0380PA00X+003425Y+079925X0540Y    R270 S3      
317GND              J6    -9   MD0380PA00X+002638Y+044374X0540Y    R270 S3      
317GND              J6    -8   MD0380PA00X+003425Y+043587X0540Y    R270 S3      
317GND              J5    -9   MD0380PA00X+002638Y+008035X0540Y    R270 S3      
317GND              J5    -8   MD0380PA00X+003425Y+007248X0540Y    R270 S3      
317GND              J4    -9   MD0380PA00X+017716Y+007248X0540Y    R090 S3      
317GND              J4    -8   MD0380PA00X+016929Y+008035X0540Y    R090 S3      
317GND              J3    -9   MD0380PA00X+017716Y+043587X0540Y    R090 S3      
317GND              J3    -8   MD0380PA00X+016929Y+044374X0540Y    R090 S3      
317GND              J2    -9   MD0380PA00X+017716Y+079925X0540Y    R090 S3      
317GND              J2    -8   MD0380PA00X+016929Y+080713X0540Y    R090 S3      
317GND              J1    -9   MD0380PA00X+017716Y+116264X0540Y    R090 S3      
317GND              J1    -8   MD0380PA00X+016929Y+117051X0540Y    R090 S3      
327GND              C2087 -2          A01X+008550Y+083358X0198Y0197R090 S1      
327GND              C2088 -2          A01X+008550Y+047058X0198Y0197R090 S1      
327GND              C93   -1          A01X+007408Y+075150X0198Y0197R180 S1      
327GND              R315  -1          A01X+000942Y+073400X0198Y0197     S1      
327GND              R316  -1          A01X+000942Y+074100X0198Y0197     S1      
327GND              R317  -1          A01X+000942Y+074800X0198Y0197     S1      
327GND              R5471 -2          A01X+007500Y+056492X0198Y0197R270 S1      
327GND              C1933 -1          A01X+007850Y+061158X0198Y0197R270 S1      
327GND              R5524 -2          A01X+006800Y+056492X0198Y0197R270 S1      
327GND              C1502 -2          A01X+007408Y+072900X0198Y0197     S1      
327GND              R2355 -2          A01X+001342Y+072700X0198Y0197R180 S1      
327GND              R2362 -2          A01X+001342Y+071500X0198Y0197R180 S1      
327GND              C2010 -2          A01X+013458Y+065650X0198Y0197     S1      
327GND              R5115 -2          A01X+018408Y+065200X0198Y0197     S1      
327GND              R5116 -2          A01X+018408Y+065950X0198Y0197     S1      
327GND              R5117 -2          A01X+018408Y+066350X0198Y0197     S1      
327GND              C2020 -2          A01X+013742Y+119750X0198Y0197R180 S1      
327GND              C2023 -2          A01X+012900Y+112892X0198Y0197R270 S1      
327GND              C2029 -2          A01X+013692Y+081511X0198Y0197R180 S1      
327GND              C2030 -2          A01X+012842Y+082011X0198Y0197R180 S1      
327GND              C2040 -2          A01X+013742Y+047073X0198Y0197R180 S1      
327GND              C2042 -2          A01X+012842Y+045673X0198Y0197R180 S1      
327GND              C2091 -2          A01X+011350Y+040042X0198Y0197R270 S1      
327GND              C2093 -2          A01X+011850Y+112842X0198Y0197R270 S1      
327GND              C1940 -2          A01X+006308Y+066650X0198Y0197     S1      
327GND              C1942 -2          A01X+006308Y+067250X0198Y0197     S1      
327GND              C1946 -2          A01X+006308Y+067900X0198Y0197     S1      
327GND              C1948 -2          A01X+006308Y+068500X0198Y0197     S1      
327GND              C2065 -2          A01X+017586Y+100592X0198Y0197R270 S1      
327GND              C2064 -2          A01X+015593Y+100950X0198Y0197     S1      
327GND              C2066 -2          A01X+015641Y+099365X0198Y0197R180 S1      
327GND              C2067 -2          A01X+013648Y+099722X0198Y0197R090 S1      
327GND              C2068 -2          A01X+017586Y+027915X0198Y0197R270 S1      
327GND              C2069 -2          A01X+015593Y+028273X0198Y0197     S1      
327GND              C188  -2          A01X+014892Y+072900X0198Y0197R180 S1      
327GND              R519  -1          A01X+017908Y+071300X0198Y0197R180 S1      
327GND              R521  -1          A01X+017908Y+072000X0198Y0197R180 S1      
327GND              C1953 -2          A01X+016708Y+075400X0198Y0197     S1      
327GND              R4965 -1          A01X+017908Y+074000X0198Y0197R180 S1      
327GND              R4967 -1          A01X+017908Y+074700X0198Y0197R180 S1      
327GND              C2082 -2          A01X+019108Y+070600X0198Y0197     S1      
327GND              C2083 -2          A01X+009542Y+074500X0198Y0197R180 S1      
327GND              C2084 -2          A01X+009542Y+073800X0198Y0197R180 S1      
327GND              C2060 -2          A01X+001279Y+026730X0198Y0197R090 S1      
327GND              C2061 -2          A01X+003272Y+026373X0198Y0197R180 S1      
327GND              C2070 -2          A01X+003272Y+099050X0198Y0197R180 S1      
327GND              C2032 -2          A01X+006612Y+040138X0198Y0197     S1      
327GND              C2033 -2          A01X+006662Y+042038X0198Y0197     S1      
327GND              C2034 -2          A01X+007508Y+041000X0198Y0197     S1      
327GND              C2044 -2          A01X+006612Y+076476X0198Y0197     S1      
327GND              C2045 -2          A01X+006662Y+078376X0198Y0197     S1      
327GND              C2047 -2          A01X+007708Y+083400X0198Y0197     S1      
327GND              C2056 -2          A01X+006612Y+112865X0198Y0197     S1      
327GND              C2057 -2          A01X+006662Y+114765X0198Y0197     S1      
327GND              C2058 -2          A01X+007512Y+114265X0198Y0197     S1      
327GND              C2059 -2          A01X+006500Y+120008X0198Y0197R090 S1      
317GND              VIA   -    MD0100PA00X+000600Y+072700X0200Y         S0      
317GND              VIA   -    MD0100PA00X+001342Y+071250X0200Y         S0      
317GND              VIA   -    MD0100PA00X+019550Y+122250X0200Y         S0      
317GND              VIA   -    MD0100PA00X+019550Y+122000X0200Y         S0      
317GND              VIA   -    MD0100PA00X+019250Y+121500X0200Y         S0      
317GND              VIA   -    MD0100PA00X+000800Y+122250X0200Y         S0      
317GND              VIA   -    MD0100PA00X+000800Y+122000X0200Y         S0      
317GND              VIA   -    MD0100PA00X+001100Y+121500X0200Y         S0      
317GND              VIA   -    MD0100PA00X+012500Y+119800X0200Y         S0      
317GND              VIA   -    MD0100PA00X+013500Y+119750X0200Y         S0      
327GND              D266  -A          A01X+014533Y+118350X0220Y0240     S1      
317GND              VIA   -    MD0100PA00X+014250Y+118350X0200Y         S0      
327GND              D263  -A          A01X+014533Y+115100X0220Y0240     S1      
317GND              VIA   -    MD0100PA00X+014273Y+115100X0200Y         S0      
327GND              U369  -S          A01X+013235Y+115944X0240Y0320R270 S1      
317GND              VIA   -    MD0100PA00X+013235Y+115674X0200Y         S0      
317GND              VIA   -    MD0100PA00X+007350Y+120008X0200Y    R180 S0      
327GND              D262  -A          A01X+007517Y+114750X0220Y0240R180 S1      
317GND              VIA   -    MD0100PA00X+007777Y+114750X0200Y         S0      
317GND              VIA   -    MD0100PA00X+006902Y+114765X0200Y    R180 S0      
327GND              U60   -3          A01X+009106Y+118126X0160Y0200R180 S1      
317GND              VIA   -    MD0100PA00X+009473Y+117391X0200Y    R090 S0      
327GND              U402  -3          A01X+011294Y+114374X0160Y0200     S1      
317GND              VIA   -    MD0100PA00X+011294Y+114624X0200Y    R270 S0      
327GND              U367  -S          A01X+007115Y+116256X0240Y0320R090 S1      
317GND              VIA   -    MD0100PA00X+007115Y+116550X0200Y    R180 S0      
327GND              U366  -S          A01X+007115Y+117856X0240Y0320R090 S1      
317GND              VIA   -    M      A01X+007431Y+117856X0200Y    R180 S2      
017GND              VIA   -    M      A06X+007431Y+117856X0260Y    R180 S2      
017GND                    -    MD0100PA00X+007431Y+117856                       
327GND              D258  -A          A01X+005817Y+118400X0220Y0240R180 S1      
317GND              VIA   -    MD0100PA00X+005750Y+118100X0200Y         S0      
327GND              D257  -A          A01X+005817Y+117350X0220Y0240R180 S1      
317GND              VIA   -    MD0100PA00X+006100Y+117250X0200Y         S0      
317GND              VIA   -    M      A01X+012650Y+112900X0200Y         S2      
017GND              VIA   -    M      A06X+012650Y+112900X0260Y         S2      
017GND                    -    MD0100PA00X+012650Y+112900                       
327GND              D265  -A          A01X+014133Y+112850X0220Y0240     S1      
317GND              VIA   -    MD0100PA00X+014209Y+113128X0200Y         S0      
327GND              U368  -S          A01X+013235Y+114344X0240Y0320R270 S1      
317GND              VIA   -    MD0100PA00X+013550Y+114344X0200Y         S0      
327GND              D264  -A          A01X+014533Y+114150X0220Y0240     S1      
317GND              VIA   -    MD0100PA00X+014165Y+114150X0200Y         S0      
327GND              D261  -A          A01X+007522Y+112865X0220Y0240R180 S1      
317GND              VIA   -    MD0100PA00X+007782Y+112865X0200Y    R180 S0      
317GND              VIA   -    MD0100PA00X+006854Y+112865X0200Y    R180 S0      
317GND              VIA   -    MD0100PA00X+007752Y+114265X0200Y    R180 S0      
317GND              VIA   -    MD0100PA00X+012100Y+112842X0200Y    R270 S0      
327GND              D260  -A          A01X+006222Y+114265X0220Y0240R180 S1      
317GND              VIA   -    MD0100PA00X+006222Y+113995X0200Y    R180 S0      
317GND              VIA   -    MD0100PA00X+018136Y+106276X0200Y         S0      
317GND              VIA   -    MD0100PA00X+018436Y+106276X0200Y         S0      
317GND              VIA   -    MD0100PA00X+018736Y+106276X0200Y         S0      
317GND              VIA   -    MD0100PA00X+019036Y+106276X0200Y         S0      
327GND              PD1   -A          A06X+018380Y+106921X0990Y1300R090 S2      
327GND              PD13  -A          A06X+002168Y+106918X0990Y1300R090 S2      
317GND              VIA   -    MD0100PA00X+001400Y+106272X0200Y         S0      
317GND              VIA   -    MD0100PA00X+001700Y+106272X0200Y         S0      
317GND              VIA   -    MD0100PA00X+002000Y+106272X0200Y         S0      
317GND              VIA   -    MD0100PA00X+002300Y+106272X0200Y         S0      
317GND              VIA   -    MD0100PA00X+002600Y+106272X0200Y         S0      
317GND              VIA   -    MD0100PA00X+015548Y+099615X0200Y    R180 S0      
327GND              U377  -3          A06X+016115Y+100494X0130Y0460R090 S2      
317GND              VIA   -    MD0100PA00X+016636Y+100494X0200Y         S0      
327GND              U394  -3          A06X+017290Y+100346X0240Y0240R270 S2      
317GND              VIA   -    MD0100PA00X+017290Y+100650X0200Y         S0      
317GND              VIA   -    MD0100PA00X+015686Y+100700X0200Y         S0      
327GND              PC8   -2          A06X+014798Y+103200X0400Y0500R270 S2      
317GND              VIA   -    MD0100PA00X+014648Y+102850X0200Y         S0      
317GND              VIA   -    MD0100PA00X+014948Y+102850X0200Y         S0      
327GND              U379  -3          A06X+015119Y+099821X0130Y0460R270 S2      
317GND              VIA   -    MD0100PA00X+014598Y+099821X0200Y    R180 S0      
327GND              U395  -3          A06X+013944Y+099969X0240Y0240R090 S2      
317GND              VIA   -    MD0100PA00X+013944Y+099665X0200Y    R180 S0      
317GND              VIA   -    MD0100PA00X+012888Y+101590X0200Y         S0      
317GND              VIA   -    MD0100PA00X+012588Y+101590X0200Y         S0      
317GND              VIA   -    MD0100PA00X+012888Y+101290X0200Y         S0      
317GND              VIA   -    MD0100PA00X+012588Y+101290X0200Y         S0      
317GND              VIA   -    MD0100PA00X+013488Y+101590X0200Y         S0      
317GND              VIA   -    MD0100PA00X+013188Y+101590X0200Y         S0      
317GND              VIA   -    MD0100PA00X+013488Y+101290X0200Y         S0      
317GND              VIA   -    MD0100PA00X+013188Y+101290X0200Y         S0      
327GND              U397  -3          A06X+001795Y+099854X0240Y0240R090 S2      
317GND              VIA   -    MD0100PA00X+001528Y+099550X0200Y    R180 S0      
327GND              U383  -3          A06X+002750Y+099506X0130Y0460R270 S2      
317GND              VIA   -    MD0100PA00X+002650Y+099750X0200Y    R180 S0      
317GND              VIA   -    MD0100PA00X+003179Y+099300X0200Y    R180 S0      
317GND              VIA   -    MD0100PA00X+003937Y+097280X0200Y    R180 S0      
317GND              VIA   -    MD0100PA00X+004237Y+097280X0200Y    R180 S0      
317GND              VIA   -    MD0100PA00X+005937Y+099640X0200Y    R180 S0      
317GND              VIA   -    MD0100PA00X+005637Y+099640X0200Y    R180 S0      
317GND              VIA   -    MD0100PA00X+006237Y+099640X0200Y    R180 S0      
317GND              VIA   -    MD0100PA00X+006537Y+099640X0200Y    R180 S0      
317GND              VIA   -    MD0100PA00X+018318Y+094310X0200Y    R180 S0      
317GND              VIA   -    MD0100PA00X+018318Y+094010X0200Y    R180 S0      
327GND              PD8   -A          A06X+018689Y+089320X0990Y1300R180 S2      
317GND              VIA   -    MD0100PA00X+019396Y+089902X0200Y    R090 S0      
317GND              VIA   -    MD0100PA00X+019396Y+089602X0200Y    R090 S0      
317GND              VIA   -    MD0100PA00X+019396Y+089302X0200Y    R090 S0      
317GND              VIA   -    MD0100PA00X+019396Y+089002X0200Y    R090 S0      
317GND              VIA   -    MD0100PA00X+019396Y+088702X0200Y    R090 S0      
317GND              VIA   -    MD0100PA00X+001205Y+093427X0200Y    R180 S0      
317GND              VIA   -    MD0100PA00X+001205Y+093727X0200Y    R180 S0      
327GND              PD12  -A          A06X+001384Y+088758X0990Y1300     S2      
317GND              VIA   -    M      A01X+013452Y+081511X0200Y         S2      
017GND              VIA   -    M      A06X+013452Y+081511X0260Y         S2      
017GND                    -    MD0100PA00X+013452Y+081511                       
327GND              D273  -A          A01X+012883Y+083450X0220Y0240     S1      
317GND              VIA   -    M      A01X+012600Y+083450X0200Y         S2      
017GND              VIA   -    M      A06X+012600Y+083450X0260Y         S2      
017GND                    -    MD0100PA00X+012600Y+083450                       
327GND              D272  -A          A01X+014133Y+082011X0220Y0240     S1      
317GND              VIA   -    M      A01X+014133Y+082281X0200Y         S2      
017GND              VIA   -    M      A06X+014133Y+082281X0260Y         S2      
017GND                    -    MD0100PA00X+014133Y+082281                       
327GND              D274  -A          A01X+012783Y+081500X0220Y0240     S1      
317GND              VIA   -    MD0100PA00X+012523Y+081500X0200Y         S0      
317GND              VIA   -    M      A01X+012550Y+082011X0200Y         S2      
017GND              VIA   -    M      A06X+012550Y+082011X0260Y         S2      
017GND                    -    MD0100PA00X+012550Y+082011                       
327GND              U62   -3          A01X+009106Y+081826X0160Y0200R180 S1      
317GND              VIA   -    MD0100PA00X+009295Y+082171X0200Y    R090 S0      
317GND              VIA   -    M      A01X+008200Y+083358X0200Y    R090 S2      
017GND              VIA   -    M      A06X+008200Y+083358X0260Y    R090 S2      
017GND                    -    MD0100PA00X+008200Y+083358                       
327GND              U364  -S          A01X+007165Y+081806X0240Y0320R090 S1      
317GND              VIA   -    MD0100PA00X+007165Y+082100X0200Y         S0      
317GND              VIA   -    MD0100PA00X+007702Y+083676X0200Y    R180 S0      
317GND              VIA   -    MD0100PA00X+006222Y+083088X0200Y    R180 S0      
327GND              D253  -A          A01X+006222Y+083376X0220Y0240R180 S1      
327GND              D252  -A          A01X+005817Y+082061X0220Y0240R180 S1      
317GND              VIA   -    MD0100PA00X+006077Y+082061X0200Y         S0      
327GND              D251  -A          A01X+005817Y+081000X0220Y0240R180 S1      
317GND              VIA   -    MD0100PA00X+006100Y+081000X0200Y         S0      
327GND              D269  -A          A01X+014483Y+080150X0220Y0240     S1      
317GND              VIA   -    MD0100PA00X+014199Y+080030X0200Y         S0      
327GND              D270  -A          A01X+014533Y+079150X0220Y0240     S1      
317GND              VIA   -    MD0100PA00X+014273Y+079150X0200Y         S0      
317GND              VIA   -    MD0100PA00X+012970Y+077780X0200Y         S0      
327GND              D271  -A          A01X+014483Y+076650X0220Y0240     S1      
317GND              VIA   -    MD0100PA00X+014483Y+076351X0200Y         S0      
317GND              VIA   -    MD0100PA00X+016708Y+075650X0200Y         S0      
327GND              U371  -S          A01X+013235Y+079594X0240Y0320R270 S1      
317GND              VIA   -    M      A01X+013235Y+079324X0200Y         S2      
017GND              VIA   -    M      A06X+013235Y+079324X0260Y         S2      
017GND                    -    MD0100PA00X+013235Y+079324                       
317GND              VIA   -    MD0100PA00X+006869Y+076476X0200Y    R180 S0      
317GND              VIA   -    M      A01X+006902Y+078376X0200Y    R180 S2      
017GND              VIA   -    M      A06X+006902Y+078376X0260Y    R180 S2      
017GND                    -    MD0100PA00X+006902Y+078376                       
317GND              VIA   -    M      A01X+007800Y+078250X0200Y    R180 S2      
017GND              VIA   -    M      A06X+007800Y+078250X0260Y    R180 S2      
017GND                    -    MD0100PA00X+007800Y+078250                       
327GND              D255  -A          A01X+007522Y+076476X0220Y0240R180 S1      
317GND              VIA   -    M      A01X+007782Y+076476X0200Y    R180 S2      
017GND              VIA   -    M      A06X+007782Y+076476X0260Y    R180 S2      
017GND                    -    MD0100PA00X+007782Y+076476                       
327GND              U401  -3          A01X+011194Y+078074X0160Y0200     S1      
317GND              VIA   -    M      A01X+010750Y+078253X0200Y    R270 S2      
017GND              VIA   -    M      A06X+010750Y+078253X0260Y    R270 S2      
017GND                    -    MD0100PA00X+010750Y+078253                       
327GND              U365  -S          A01X+007165Y+080206X0240Y0320R090 S1      
317GND              VIA   -    M      A01X+006848Y+080095X0200Y    R180 S2      
017GND              VIA   -    M      A06X+006848Y+080095X0260Y    R180 S2      
017GND                    -    MD0100PA00X+006848Y+080095                       
317GND              VIA   -    MD0100PA00X+005867Y+077580X0200Y    R180 S0      
327GND              D254  -A   M      A01X+005867Y+077850X0220Y0240R180 S1      
317GND              VIA   -    M      A01X+019348Y+070600X0200Y         S2      
017GND              VIA   -    M      A06X+019348Y+070600X0260Y         S2      
017GND                    -    MD0100PA00X+019348Y+070600                       
317GND              VIA   -    M      A01X+019258Y+073300X0200Y         S2      
017GND              VIA   -    M      A06X+019258Y+073300X0260Y         S2      
017GND                    -    MD0100PA00X+019258Y+073300                       
317GND              VIA   -    M      A01X+018148Y+074700X0200Y         S2      
017GND              VIA   -    M      A06X+018148Y+074700X0260Y         S2      
017GND                    -    MD0100PA00X+018148Y+074700                       
317GND              VIA   -    MD0100PA00X+018148Y+074000X0200Y         S0      
317GND              VIA   -    M      A01X+018148Y+071300X0200Y         S2      
017GND              VIA   -    M      A06X+018148Y+071300X0260Y         S2      
017GND                    -    MD0100PA00X+018148Y+071300                       
327GND              U390  -7          A01X+013100Y+070732X0140Y0590R270 S1      
317GND              VIA   -    M      A01X+012650Y+070650X0200Y         S2      
017GND              VIA   -    M      A06X+012650Y+070650X0260Y         S2      
017GND                    -    MD0100PA00X+012650Y+070650                       
317GND              VIA   -    MD0100PA00X+018148Y+072000X0200Y         S0      
327GND              U389  -7          A01X+013150Y+073832X0140Y0590R270 S1      
317GND              VIA   -    M      A01X+012798Y+073623X0200Y         S2      
017GND              VIA   -    M      A06X+012798Y+073623X0260Y         S2      
017GND                    -    MD0100PA00X+012798Y+073623                       
317GND              VIA   -    M      A01X+014600Y+072900X0200Y         S2      
017GND              VIA   -    M      A06X+014600Y+072900X0260Y         S2      
017GND                    -    MD0100PA00X+014600Y+072900                       
317GND              VIA   -    MD0100PA00X+009300Y+074500X0200Y         S0      
317GND              VIA   -    M      A01X+007408Y+073200X0200Y         S2      
017GND              VIA   -    M      A06X+007408Y+073200X0260Y         S2      
017GND                    -    MD0100PA00X+007408Y+073200                       
317GND              VIA   -    M      A01X+009302Y+073800X0200Y         S2      
017GND              VIA   -    M      A06X+009302Y+073800X0260Y         S2      
017GND                    -    MD0100PA00X+009302Y+073800                       
317GND              VIA   -    MD0100PA00X+007650Y+074650X0200Y         S0      
327GND              U59   -4          A01X+003010Y+073550X0220Y0680R270 S1      
317GND              VIA   -    MD0100PA00X+002650Y+073250X0200Y         S0      
327GND              U7    -12         A01X+002900Y+069442X0140Y0590R270 S1      
317GND              VIA   -    MD0100PA00X+003350Y+069442X0200Y         S0      
317GND              VIA   -    MD0100PA00X+000602Y+073400X0200Y         S0      
317GND              VIA   -    MD0100PA00X+000602Y+074100X0200Y         S0      
317GND              VIA   -    MD0100PA00X+000602Y+074800X0200Y         S0      
317GND              VIA   -    M      A01X+018705Y+066350X0200Y    R180 S2      
017GND              VIA   -    M      A06X+018705Y+066350X0260Y    R180 S2      
017GND                    -    MD0100PA00X+018705Y+066350                       
317GND              VIA   -    MD0100PA00X+018705Y+065950X0200Y    R180 S0      
317GND              VIA   -    M      A01X+018705Y+065200X0200Y    R180 S2      
017GND              VIA   -    M      A06X+018705Y+065200X0260Y    R180 S2      
017GND                    -    MD0100PA00X+018705Y+065200                       
327GND              U8    -12         A01X+015450Y+068958X0140Y0590R090 S1      
317GND              VIA   -    M      A01X+015696Y+069204X0200Y    R180 S2      
017GND              VIA   -    M      A06X+015696Y+069204X0260Y    R180 S2      
017GND                    -    MD0100PA00X+015696Y+069204                       
317GND              VIA   -    M      A01X+013458Y+065900X0200Y         S2      
017GND              VIA   -    M      A06X+013458Y+065900X0260Y         S2      
017GND                    -    MD0100PA00X+013458Y+065900                       
317GND              VIA   -    MD0100PA00X+006548Y+067900X0200Y    R180 S0      
317GND              VIA   -    MD0100PA00X+006548Y+068500X0200Y    R180 S0      
327GND              U26   -2          A01X+004274Y+068200X0160Y0200R090 S1      
317GND              VIA   -    M      A01X+004524Y+068200X0200Y    R180 S2      
017GND              VIA   -    M      A06X+004524Y+068200X0260Y    R180 S2      
017GND                    -    MD0100PA00X+004524Y+068200                       
327GND              U25   -2          A01X+004274Y+066950X0160Y0200R090 S1      
317GND              VIA   -    MD0100PA00X+004524Y+066950X0200Y    R180 S0      
327GND              U24   -2          A01X+004274Y+065700X0160Y0200R090 S1      
317GND              VIA   -    M      A01X+004524Y+065700X0200Y    R180 S2      
017GND              VIA   -    M      A06X+004524Y+065700X0260Y    R180 S2      
017GND                    -    MD0100PA00X+004524Y+065700                       
317GND              VIA   -    MD0100PA00X+006550Y+067150X0200Y    R180 S0      
317GND              VIA   -    MD0100PA00X+006548Y+066650X0200Y    R180 S0      
327GND              U23   -2          A01X+004274Y+064600X0160Y0200R090 S1      
317GND              VIA   -    MD0100PA00X+004550Y+064600X0200Y    R180 S0      
317GND              VIA   -    MD0100PA00X+007486Y+061158X0200Y    R090 S0      
327GND              U321  -12         A01X+011158Y+058700X0140Y0590     S1      
317GND              VIA   -    M      A01X+011400Y+059100X0200Y    R090 S2      
017GND              VIA   -    M      A06X+011400Y+059100X0260Y    R090 S2      
017GND                    -    MD0100PA00X+011400Y+059100                       
317GND              H4    -1   MD1190PA00X+016083Y+062071X3550Y8270     S3      
317GND              H3    -1   MD1190PA00X+004272Y+062071X3550Y8270     S3      
317GND              VIA   -    M      A01X+007350Y+056220X0200Y    R090 S2      
017GND              VIA   -    M      A06X+007350Y+056220X0260Y    R090 S2      
017GND                    -    MD0100PA00X+007350Y+056220                       
317GND              VIA   -    MD0100PA00X+019550Y+049750X0200Y         S0      
317GND              VIA   -    MD0100PA00X+019550Y+049500X0200Y         S0      
317GND              VIA   -    MD0100PA00X+019500Y+049050X0200Y         S0      
327GND              C2036 -2          A01X+019150Y+049600X0400Y0500R180 S1      
317GND              VIA   -    M      A01X+013535Y+046865X0200Y         S2      
017GND              VIA   -    M      A06X+013535Y+046865X0260Y         S2      
017GND                    -    MD0100PA00X+013535Y+046865                       
317GND              VIA   -    M      A01X+008550Y+047298X0200Y    R090 S2      
017GND              VIA   -    M      A06X+008550Y+047298X0260Y    R090 S2      
017GND                    -    MD0100PA00X+008550Y+047298                       
317GND              VIA   -    M      A01X+006525Y+047038X0200Y    R180 S2      
017GND              VIA   -    M      A06X+006525Y+047038X0260Y    R180 S2      
017GND                    -    MD0100PA00X+006525Y+047038                       
327GND              D247  -A          A01X+006222Y+047038X0220Y0240R180 S1      
317GND              VIA   -    MD0100PA00X+002050Y+049500X0200Y    R180 S0      
317GND              VIA   -    MD0100PA00X+002050Y+049750X0200Y    R180 S0      
317GND              VIA   -    MD0100PA00X+001800Y+049150X0200Y    R180 S0      
317GND              VIA   -    M      A01X+012520Y+045380X0200Y         S2      
017GND              VIA   -    M      A06X+012520Y+045380X0260Y         S2      
017GND                    -    MD0100PA00X+012520Y+045380                       
327GND              D275  -A          A01X+014533Y+042800X0220Y0240     S1      
317GND              VIA   -    MD0100PA00X+014273Y+042800X0200Y         S0      
317GND              VIA   -    MD0100PA00X+014533Y+041650X0200Y         S0      
327GND              D276  -A          A01X+014533Y+041373X0220Y0240     S1      
327GND              U372  -S          A01X+013285Y+041394X0240Y0320R270 S1      
317GND              VIA   -    MD0100PA00X+012931Y+041454X0200Y         S0      
327GND              U373  -S          A01X+013285Y+042994X0240Y0320R270 S1      
317GND              VIA   -    MD0100PA00X+013600Y+042994X0200Y         S0      
327GND              D250  -A          A01X+007517Y+042023X0220Y0240R180 S1      
317GND              VIA   -    MD0100PA00X+007777Y+042023X0200Y         S0      
317GND              VIA   -    MD0100PA00X+007850Y+041000X0200Y    R180 S0      
317GND              VIA   -    M      A01X+006902Y+042038X0200Y    R180 S2      
017GND              VIA   -    M      A06X+006902Y+042038X0260Y    R180 S2      
017GND                    -    MD0100PA00X+006902Y+042038                       
327GND              U400  -3          A01X+011244Y+041574X0160Y0200     S1      
317GND              VIA   -    M      A01X+011244Y+041843X0200Y    R270 S2      
017GND              VIA   -    M      A06X+011244Y+041843X0260Y    R270 S2      
017GND                    -    MD0100PA00X+011244Y+041843                       
317GND              VIA   -    MD0100PA00X+012550Y+046960X0200Y         S0      
327GND              U64   -3          A01X+009106Y+045526X0160Y0200R180 S1      
317GND              VIA   -    M      A01X+009106Y+045276X0200Y    R090 S2      
017GND              VIA   -    M      A06X+009106Y+045276X0260Y    R090 S2      
017GND                    -    MD0100PA00X+009106Y+045276                       
327GND              U363  -S          A01X+007165Y+043756X0240Y0320R090 S1      
317GND              VIA   -    M      A01X+007498Y+043756X0200Y    R180 S2      
017GND              VIA   -    M      A06X+007498Y+043756X0260Y    R180 S2      
017GND                    -    MD0100PA00X+007498Y+043756                       
327GND              D246  -A          A01X+005817Y+045723X0220Y0240R180 S1      
317GND              VIA   -    MD0100PA00X+006077Y+045723X0200Y         S0      
317GND              VIA   -    MD0100PA00X+006222Y+041268X0200Y    R180 S0      
327GND              D248  -A          A01X+006222Y+041538X0220Y0240R180 S1      
327GND              D245  -A          A01X+005817Y+044373X0220Y0240R180 S1      
317GND              VIA   -    M      A01X+006077Y+044373X0200Y         S2      
017GND              VIA   -    M      A06X+006077Y+044373X0260Y         S2      
017GND                    -    MD0100PA00X+006077Y+044373                       
317GND              VIA   -    M      A01X+006870Y+040000X0200Y    R180 S2      
017GND              VIA   -    M      A06X+006870Y+040000X0260Y    R180 S2      
017GND                    -    MD0100PA00X+006870Y+040000                       
317GND              VIA   -    MD0100PA00X+011300Y+039450X0200Y    R270 S0      
317GND              VIA   -    M      A01X+008450Y+040400X0200Y    R180 S2      
017GND              VIA   -    M      A06X+008450Y+040400X0260Y    R180 S2      
017GND                    -    MD0100PA00X+008450Y+040400                       
327GND              PC16  -2          A06X+014798Y+030523X0400Y0500R270 S2      
317GND              VIA   -    MD0100PA00X+014948Y+030173X0200Y         S0      
317GND              VIA   -    MD0100PA00X+014648Y+030173X0200Y         S0      
327GND              PD9   -A          A06X+018186Y+034241X0990Y1300R090 S2      
317GND              VIA   -    MD0100PA00X+018346Y+033583X0200Y         S0      
317GND              VIA   -    MD0100PA00X+018646Y+033583X0200Y         S0      
317GND              VIA   -    MD0100PA00X+018046Y+033583X0200Y         S0      
317GND              VIA   -    MD0100PA00X+017746Y+033583X0200Y         S0      
327GND              PD11  -A          A06X+002168Y+034241X0990Y1300R090 S2      
317GND              VIA   -    MD0100PA00X+002600Y+033593X0200Y         S0      
317GND              VIA   -    MD0100PA00X+002300Y+033593X0200Y         S0      
317GND              VIA   -    MD0100PA00X+002000Y+033593X0200Y         S0      
317GND              VIA   -    MD0100PA00X+001700Y+033593X0200Y         S0      
317GND              VIA   -    MD0100PA00X+001400Y+033593X0200Y         S0      
327GND              U396  -3          A06X+017290Y+027668X0240Y0240R270 S2      
317GND              VIA   -    MD0100PA00X+017290Y+027973X0200Y         S0      
327GND              U381  -3          A06X+016115Y+027817X0130Y0460R090 S2      
317GND              VIA   -    MD0100PA00X+016650Y+027648X0200Y         S0      
317GND              VIA   -    MD0100PA00X+015686Y+028023X0200Y         S0      
317GND              VIA   -    M      A01X+013648Y+028623X0200Y         S2      
017GND              VIA   -    M      A06X+013648Y+028623X0260Y         S2      
017GND                    -    MD0100PA00X+013648Y+028623                       
317GND              VIA   -    MD0100PA00X+013048Y+028623X0200Y         S0      
317GND              VIA   -    MD0100PA00X+013348Y+028623X0200Y         S0      
317GND              VIA   -    MD0100PA00X+013648Y+028923X0200Y         S0      
317GND              VIA   -    MD0100PA00X+013048Y+028923X0200Y         S0      
317GND              VIA   -    MD0100PA00X+013348Y+028923X0200Y         S0      
317GND              VIA   -    M      A01X+012748Y+028623X0200Y         S2      
017GND              VIA   -    M      A06X+012748Y+028623X0260Y         S2      
017GND                    -    MD0100PA00X+012748Y+028623                       
317GND              VIA   -    MD0100PA00X+012748Y+028923X0200Y         S0      
317GND              VIA   -    MD0100PA00X+005517Y+027223X0200Y    R180 S0      
317GND              VIA   -    MD0100PA00X+006417Y+027223X0200Y    R180 S0      
317GND              VIA   -    MD0100PA00X+006117Y+027223X0200Y    R180 S0      
317GND              VIA   -    MD0100PA00X+005817Y+027223X0200Y    R180 S0      
317GND              VIA   -    MD0100PA00X+005217Y+025923X0200Y    R180 S0      
317GND              VIA   -    MD0100PA00X+005517Y+025923X0200Y    R180 S0      
317GND              VIA   -    MD0100PA00X+006117Y+025923X0200Y    R180 S0      
317GND              VIA   -    MD0100PA00X+005817Y+025923X0200Y    R180 S0      
327GND              PC61  -2          A06X+004067Y+024123X0400Y0500R090 S2      
317GND              VIA   -    MD0100PA00X+004217Y+024473X0200Y    R180 S0      
317GND              VIA   -    MD0100PA00X+003917Y+024473X0200Y    R180 S0      
317GND              VIA   -    MD0100PA00X+001000Y+026730X0200Y    R180 S0      
317GND              VIA   -    MD0100PA00X+003200Y+026100X0200Y    R180 S0      
327GND              U359  -3          A06X+002750Y+026829X0130Y0460R270 S2      
317GND              VIA   -    MD0100PA00X+002791Y+027068X0200Y    R180 S0      
327GND              PD10  -A          A06X+018299Y+016963X0990Y1300R180 S2      
317GND              VIA   -    MD0100PA00X+018966Y+017384X0200Y    R090 S0      
317GND              VIA   -    MD0100PA00X+019216Y+017384X0200Y    R090 S0      
317GND              VIA   -    MD0100PA00X+018966Y+017084X0200Y    R090 S0      
317GND              VIA   -    MD0100PA00X+019216Y+017084X0200Y    R090 S0      
317GND              VIA   -    MD0100PA00X+018966Y+016784X0200Y    R090 S0      
317GND              VIA   -    MD0100PA00X+019216Y+016784X0200Y    R090 S0      
317GND              VIA   -    MD0100PA00X+018966Y+016484X0200Y    R090 S0      
317GND              VIA   -    MD0100PA00X+019216Y+016484X0200Y    R090 S0      
317GND              VIA   -    MD0100PA00X+019122Y+015749X0200Y    R090 S0      
317GND              VIA   -    MD0100PA00X+019372Y+015749X0200Y    R090 S0      
317GND              VIA   -    MD0100PA00X+001479Y+020703X0200Y    R180 S0      
317GND              VIA   -    MD0100PA00X+001479Y+021003X0200Y    R180 S0      
317GND              VIA   -    MD0100PA00X+006180Y+002593X0200Y    R090 S0      
317GND              VIA   -    MD0100PA00X+005493Y+000301X0200Y    R090 S0      
317GND              VIA   -    MD0100PA00X+003493Y+000301X0200Y    R090 S0      
317GND              VIA   -    MD0100PA00X+001587Y+000301X0200Y    R090 S0      
317GND              VIA   -    MD0100PA00X+000300Y+131068X0200Y    R090 S0      
317GND              VIA   -    MD0100PA00X+000300Y+129068X0200Y    R090 S0      
317GND              VIA   -    MD0100PA00X+000300Y+127068X0200Y    R090 S0      
317GND              VIA   -    MD0100PA00X+000300Y+125068X0200Y    R090 S0      
317GND              VIA   -    MD0100PA00X+000300Y+123068X0200Y    R090 S0      
317GND              VIA   -    MD0100PA00X+000300Y+121068X0200Y    R090 S0      
317GND              VIA   -    MD0100PA00X+000300Y+119068X0200Y    R090 S0      
317GND              VIA   -    MD0100PA00X+000300Y+117068X0200Y    R090 S0      
317GND              VIA   -    MD0100PA00X+000300Y+115068X0200Y    R090 S0      
317GND              VIA   -    MD0100PA00X+000300Y+113068X0200Y    R090 S0      
317GND              VIA   -    MD0100PA00X+000300Y+111068X0200Y    R090 S0      
317GND              VIA   -    MD0100PA00X+000300Y+109068X0200Y    R090 S0      
317GND              VIA   -    MD0100PA00X+000300Y+107068X0200Y    R090 S0      
317GND              VIA   -    MD0100PA00X+000300Y+105068X0200Y    R090 S0      
317GND              VIA   -    MD0100PA00X+000300Y+103068X0200Y    R090 S0      
317GND              VIA   -    MD0100PA00X+000300Y+101068X0200Y    R090 S0      
317GND              VIA   -    MD0100PA00X+000300Y+099068X0200Y    R090 S0      
317GND              VIA   -    MD0100PA00X+000300Y+097068X0200Y    R090 S0      
317GND              VIA   -    MD0100PA00X+000300Y+095068X0200Y    R090 S0      
317GND              VIA   -    MD0100PA00X+000300Y+093068X0200Y    R090 S0      
317GND              VIA   -    MD0100PA00X+000300Y+091068X0200Y    R090 S0      
317GND              VIA   -    MD0100PA00X+000300Y+089068X0200Y    R090 S0      
317GND              VIA   -    MD0100PA00X+000300Y+087068X0200Y    R090 S0      
317GND              VIA   -    MD0100PA00X+000300Y+085068X0200Y    R090 S0      
317GND              VIA   -    MD0100PA00X+000300Y+083068X0200Y    R090 S0      
317GND              VIA   -    MD0100PA00X+000300Y+081068X0200Y    R090 S0      
317GND              VIA   -    MD0100PA00X+000300Y+079068X0200Y    R090 S0      
317GND              VIA   -    MD0100PA00X+000300Y+077068X0200Y    R090 S0      
317GND              VIA   -    MD0100PA00X+000300Y+075068X0200Y    R090 S0      
317GND              VIA   -    MD0100PA00X+000300Y+073068X0200Y    R090 S0      
317GND              VIA   -    MD0100PA00X+000300Y+071068X0200Y    R090 S0      
317GND              VIA   -    MD0100PA00X+000300Y+069068X0200Y    R090 S0      
317GND              VIA   -    MD0100PA00X+000300Y+067068X0200Y    R090 S0      
317GND              VIA   -    MD0100PA00X+000300Y+065068X0200Y    R090 S0      
317GND              VIA   -    MD0100PA00X+000300Y+063068X0200Y    R090 S0      
317GND              VIA   -    MD0100PA00X+000300Y+061068X0200Y    R090 S0      
317GND              VIA   -    MD0100PA00X+000300Y+059068X0200Y    R090 S0      
317GND              VIA   -    MD0100PA00X+000300Y+057068X0200Y    R090 S0      
317GND              VIA   -    MD0100PA00X+000300Y+055068X0200Y    R090 S0      
317GND              VIA   -    MD0100PA00X+000300Y+053068X0200Y    R090 S0      
317GND              VIA   -    MD0100PA00X+000300Y+051068X0200Y    R090 S0      
317GND              VIA   -    MD0100PA00X+000300Y+049068X0200Y    R090 S0      
317GND              VIA   -    MD0100PA00X+000300Y+047068X0200Y    R090 S0      
317GND              VIA   -    MD0100PA00X+000300Y+045068X0200Y    R090 S0      
317GND              VIA   -    MD0100PA00X+000300Y+043068X0200Y    R090 S0      
317GND              VIA   -    MD0100PA00X+000300Y+041068X0200Y    R090 S0      
317GND              VIA   -    MD0100PA00X+000300Y+039068X0200Y    R090 S0      
317GND              VIA   -    MD0100PA00X+000300Y+037068X0200Y    R090 S0      
317GND              VIA   -    MD0100PA00X+000300Y+035068X0200Y    R090 S0      
317GND              VIA   -    MD0100PA00X+000300Y+033068X0200Y    R090 S0      
317GND              VIA   -    MD0100PA00X+000300Y+031068X0200Y    R090 S0      
317GND              VIA   -    MD0100PA00X+000300Y+029068X0200Y    R090 S0      
317GND              VIA   -    MD0100PA00X+000300Y+027068X0200Y    R090 S0      
317GND              VIA   -    MD0100PA00X+000300Y+025068X0200Y    R090 S0      
317GND              VIA   -    MD0100PA00X+000300Y+023068X0200Y    R090 S0      
317GND              VIA   -    MD0100PA00X+000300Y+021068X0200Y    R090 S0      
317GND              VIA   -    MD0100PA00X+000300Y+019068X0200Y    R090 S0      
317GND              VIA   -    MD0100PA00X+000300Y+017068X0200Y    R090 S0      
317GND              VIA   -    MD0100PA00X+000300Y+015068X0200Y    R090 S0      
317GND              VIA   -    MD0100PA00X+000300Y+013068X0200Y    R090 S0      
317GND              VIA   -    MD0100PA00X+000300Y+011068X0200Y    R090 S0      
317GND              VIA   -    MD0100PA00X+000300Y+009068X0200Y    R090 S0      
317GND              VIA   -    MD0100PA00X+000300Y+007068X0200Y    R090 S0      
317GND              VIA   -    MD0100PA00X+000300Y+005068X0200Y    R090 S0      
317GND              VIA   -    MD0100PA00X+000300Y+003068X0200Y    R090 S0      
317GND              VIA   -    MD0100PA00X+013501Y+005098X0200Y    R090 S0      
317GND              VIA   -    MD0100PA00X+014175Y+002692X0200Y    R090 S0      
317GND              VIA   -    MD0100PA00X+014674Y+000302X0200Y    R090 S0      
317GND              VIA   -    MD0100PA00X+016580Y+000300X0200Y    R090 S0      
317GND              VIA   -    MD0100PA00X+018580Y+000300X0200Y    R090 S0      
317GND              VIA   -    MD0100PA00X+019912Y+000990X0200Y    R090 S0      
317GND              VIA   -    MD0100PA00X+020054Y+002906X0200Y    R090 S0      
317GND              VIA   -    MD0100PA00X+020054Y+004906X0200Y    R090 S0      
317GND              VIA   -    MD0100PA00X+020054Y+006906X0200Y    R090 S0      
317GND              VIA   -    MD0100PA00X+020054Y+008906X0200Y    R090 S0      
317GND              VIA   -    MD0100PA00X+020054Y+010906X0200Y    R090 S0      
317GND              VIA   -    MD0100PA00X+020054Y+012906X0200Y    R090 S0      
317GND              VIA   -    MD0100PA00X+020054Y+014906X0200Y    R090 S0      
317GND              VIA   -    MD0100PA00X+020054Y+016906X0200Y    R090 S0      
317GND              VIA   -    MD0100PA00X+020054Y+018906X0200Y    R090 S0      
317GND              VIA   -    MD0100PA00X+020054Y+020906X0200Y    R090 S0      
317GND              VIA   -    MD0100PA00X+020054Y+022906X0200Y    R090 S0      
317GND              VIA   -    MD0100PA00X+020054Y+024906X0200Y    R090 S0      
317GND              VIA   -    MD0100PA00X+020054Y+026906X0200Y    R090 S0      
317GND              VIA   -    MD0100PA00X+020054Y+028906X0200Y    R090 S0      
317GND              VIA   -    MD0100PA00X+020054Y+030906X0200Y    R090 S0      
317GND              VIA   -    MD0100PA00X+020054Y+032906X0200Y    R090 S0      
317GND              VIA   -    MD0100PA00X+020054Y+034906X0200Y    R090 S0      
317GND              VIA   -    MD0100PA00X+020054Y+036906X0200Y    R090 S0      
317GND              VIA   -    MD0100PA00X+020054Y+038906X0200Y    R090 S0      
317GND              VIA   -    MD0100PA00X+020054Y+040906X0200Y    R090 S0      
317GND              VIA   -    MD0100PA00X+020054Y+042906X0200Y    R090 S0      
317GND              VIA   -    MD0100PA00X+020054Y+044906X0200Y    R090 S0      
317GND              VIA   -    MD0100PA00X+020054Y+046906X0200Y    R090 S0      
317GND              VIA   -    MD0100PA00X+020054Y+048906X0200Y    R090 S0      
317GND              VIA   -    MD0100PA00X+020054Y+050906X0200Y    R090 S0      
317GND              VIA   -    MD0100PA00X+020054Y+052906X0200Y    R090 S0      
317GND              VIA   -    MD0100PA00X+020054Y+054906X0200Y    R090 S0      
317GND              VIA   -    MD0100PA00X+020054Y+056906X0200Y    R090 S0      
317GND              VIA   -    MD0100PA00X+020054Y+058906X0200Y    R090 S0      
317GND              VIA   -    MD0100PA00X+020054Y+060906X0200Y    R090 S0      
317GND              VIA   -    MD0100PA00X+020054Y+062906X0200Y    R090 S0      
317GND              VIA   -    MD0100PA00X+020054Y+064906X0200Y    R090 S0      
317GND              VIA   -    MD0100PA00X+020054Y+066906X0200Y    R090 S0      
317GND              VIA   -    MD0100PA00X+020054Y+068906X0200Y    R090 S0      
317GND              VIA   -    MD0100PA00X+020054Y+070906X0200Y    R090 S0      
317GND              VIA   -    MD0100PA00X+020054Y+072906X0200Y    R090 S0      
317GND              VIA   -    MD0100PA00X+020054Y+074906X0200Y    R090 S0      
317GND              VIA   -    MD0100PA00X+020054Y+076906X0200Y    R090 S0      
317GND              VIA   -    MD0100PA00X+020054Y+078906X0200Y    R090 S0      
317GND              VIA   -    MD0100PA00X+020054Y+080906X0200Y    R090 S0      
317GND              VIA   -    MD0100PA00X+020054Y+082906X0200Y    R090 S0      
317GND              VIA   -    MD0100PA00X+020054Y+084906X0200Y    R090 S0      
317GND              VIA   -    MD0100PA00X+020054Y+086906X0200Y    R090 S0      
317GND              VIA   -    MD0100PA00X+020054Y+088906X0200Y    R090 S0      
317GND              VIA   -    MD0100PA00X+020054Y+090906X0200Y    R090 S0      
317GND              VIA   -    MD0100PA00X+020054Y+092906X0200Y    R090 S0      
317GND              VIA   -    MD0100PA00X+020054Y+094706X0200Y    R090 S0      
317GND              VIA   -    MD0100PA00X+020054Y+096906X0200Y    R090 S0      
317GND              VIA   -    MD0100PA00X+020054Y+098906X0200Y    R090 S0      
317GND              VIA   -    MD0100PA00X+020054Y+100906X0200Y    R090 S0      
317GND              VIA   -    MD0100PA00X+020054Y+102906X0200Y    R090 S0      
317GND              VIA   -    MD0100PA00X+020054Y+104906X0200Y    R090 S0      
317GND              VIA   -    MD0100PA00X+020054Y+106906X0200Y    R090 S0      
317GND              VIA   -    MD0100PA00X+020054Y+108906X0200Y    R090 S0      
317GND              VIA   -    MD0100PA00X+020054Y+110906X0200Y    R090 S0      
317GND              VIA   -    MD0100PA00X+020054Y+112906X0200Y    R090 S0      
317GND              VIA   -    MD0100PA00X+020054Y+114906X0200Y    R090 S0      
317GND              VIA   -    MD0100PA00X+020054Y+116906X0200Y    R090 S0      
317GND              VIA   -    MD0100PA00X+020054Y+118906X0200Y    R090 S0      
317GND              VIA   -    MD0100PA00X+020054Y+120906X0200Y    R090 S0      
317GND              VIA   -    MD0100PA00X+020054Y+122906X0200Y    R090 S0      
317GND              VIA   -    MD0100PA00X+020054Y+124906X0200Y    R090 S0      
317GND              VIA   -    MD0100PA00X+020054Y+126906X0200Y    R090 S0      
317GND              VIA   -    MD0100PA00X+020054Y+128906X0200Y    R090 S0      
317GND              VIA   -    MD0100PA00X+020054Y+130906X0200Y    R090 S0      
317GND              VIA   -    MD0100PA00X+019447Y+132188X0200Y    R090 S0      
317GND              VIA   -    MD0100PA00X+017602Y+132377X0200Y    R090 S0      
317GND              VIA   -    MD0100PA00X+013602Y+132377X0200Y    R090 S0      
317GND              VIA   -    MD0100PA00X+011602Y+132377X0200Y    R090 S0      
317GND              VIA   -    MD0100PA00X+009602Y+132377X0200Y    R090 S0      
317GND              VIA   -    MD0100PA00X+007602Y+132377X0200Y    R090 S0      
317GND              VIA   -    MD0100PA00X+005602Y+132377X0200Y    R090 S0      
317GND              VIA   -    MD0100PA00X+003552Y+132377X0200Y    R090 S0      
317GND              VIA   -    MD0100PA00X+001602Y+132377X0200Y    R090 S0      
327GND              C1945 -2          A06X+004058Y+068450X0198Y0197R180 S2      
327GND              C1943 -2   M      A06X+004058Y+068050X0198Y0197R180 S2      
327GND              C1939 -2   M      A06X+004058Y+067650X0198Y0197R180 S2      
327GND              C1941 -2   M      A06X+004058Y+067250X0198Y0197R180 S2      
327GND              PC3   -2   M      A06X+015950Y+101642X0198Y0197R090 S2      
327GND              PR8   -2   M      A06X+015142Y+101639X0198Y0197R090 S2      
327GND              PC4   -2   M      A06X+015542Y+101639X0198Y0197R090 S2      
327GND              PC2118-2          A06X+014750Y+101642X0198Y0197R090 S2      
327GND              PC58  -2   M      A06X+006856Y+101642X0198Y0197R090 S2      
327GND              PC59  -2   M      A06X+006450Y+101642X0198Y0197R090 S2      
327GND              PR77  -2   M      A06X+006050Y+101642X0198Y0197R090 S2      
327GND              PC56  -2   M      A06X+005000Y+101642X0198Y0197R090 S2      
327GND              PC57  -2   M      A06X+004612Y+101639X0198Y0197R090 S2      
327GND              PC2125-2          A06X+003806Y+101639X0198Y0197R090 S2      
327GND              PR76  -2   M      A06X+004212Y+101639X0198Y0197R090 S2      
327GND              PR69  -2   M      A06X+002608Y+098050X0198Y0197R180 S2      
327GND              PC53  -2   M      A06X+001850Y+098358X0198Y0197R270 S2      
327GND              PC52  -2   M      A06X+001450Y+098358X0198Y0197R270 S2      
327GND              PC38  -2   M      A06X+003000Y+025684X0198Y0197R270 S2      
327GND              PC39  -2   M      A06X+003423Y+025684X0198Y0197R270 S2      
327GND              PC2122-2          A06X+004231Y+025684X0198Y0197R270 S2      
327GND              PR52  -2   M      A06X+003823Y+025684X0198Y0197R270 S2      
327GND              PC41  -2   M      A06X+001900Y+025684X0198Y0197R270 S2      
327GND              PC40  -2   M      A06X+001500Y+025684X0198Y0197R270 S2      
327GND              C2028 -2          A01X+013742Y+083411X0198Y0197R180 S1      
327GND              C2041 -2          A01X+013692Y+045173X0198Y0197R180 S1      
327GND              D249  -A          A01X+007522Y+040138X0220Y0240R180 S1      
327GND              R5667 -2   M      A01X+005550Y+038958X0198Y0197R090 S1      
327GND              U410  -S   M      A01X+005015Y+039056X0240Y0320R090 S1      
327GND              R5687 -2   M      A01X+008358Y+070400X0198Y0197     S1      
327GND              R2354 -2          A01X+008358Y+071500X0198Y0197     S1      
327GND              R5688 -2   M      A01X+008358Y+070950X0198Y0197     S1      
327GND              R5675 -2          A01X+008358Y+068800X0198Y0197     S1      
327GND              U370  -S          A01X+013335Y+078014X0240Y0320R270 S1      
327GND              C2016 -2          A01X+007650Y+007058X0198Y0197R090 S1      
327GND              D244  -A   M      A01X+007517Y+007519X0220Y0240R180 S1      
327GND              U408  -S   M      A01X+010835Y+012894X0240Y0320R270 S1      
327GND              U409  -S          A01X+009465Y+012606X0240Y0320R090 S1      
327GND              R5657 -2   M      A01X+010300Y+012992X0198Y0197R270 S1      
327GND              U375  -S   M      A01X+013235Y+007044X0240Y0320R270 S1      
327GND              C2090 -2          A01X+012508Y+006650X0198Y0197     S1      
327GND              D285  -A   M      A01X+013033Y+012450X0220Y0240     S1      
327GND              C2052 -2          A01X+013842Y+012684X0198Y0197R180 S1      
327GND              C2055 -2   M      A01X+014350Y+005492X0198Y0197R270 S1      
327FAN_0_TIMER      PC6   -1          A06X+017350Y+101958X0198Y0197R090 S2      
327FAN_0_TIMER      PU1   -23         A06X+016778Y+103171X0070Y0360R180 S2      
327P52V_HSC         PU4   -1          A06X+015322Y+096691X0118Y0945R090 S2      
327P52V_HSC         PU4   -18         A06X+014082Y+096691X0120Y0990R270 S2      
327P52V_HSC         PD4   -C          A06X+018380Y+096271X0950Y1300R090 S2      
327P52V_HSC         PU4   -2          A06X+015302Y+096061X0120Y0990R270 S2      
327P52V_HSC         PC9   -1          A06X+016626Y+096565X0400Y0500R090 S2      
327P52V_HSC         PD17  -C          A06X+005937Y+096391X0950Y1300R090 S2      
327P52V_HSC         PC63  -1          A06X+004087Y+096230X0400Y0500R090 S2      
327P52V_HSC         PU8   -1          A06X+002953Y+096376X0118Y0945R090 S2      
327P52V_HSC         PU8   -2          A06X+002933Y+095746X0120Y0990R270 S2      
327P52V_HSC         PU8   -18         A06X+001713Y+096376X0120Y0990R270 S2      
327P52V_HSC         PD15  -C          A06X+005817Y+023974X0950Y1300R090 S2      
327P52V_HSC         PC61  -1          A06X+004067Y+023423X0400Y0500R090 S2      
327P52V_HSC         PU6   -1          A06X+002953Y+023699X0118Y0945R090 S2      
327P52V_HSC         PU6   -2          A06X+002933Y+023069X0120Y0990R270 S2      
327P52V_HSC         PU6   -18         A06X+001713Y+023699X0120Y0990R270 S2      
327P52V_HSC         PD14  -C          A06X+018296Y+023714X0950Y1300R090 S2      
327P52V_HSC         PU3   -1          A06X+015322Y+023699X0118Y0945R090 S2      
327P52V_HSC         PU3   -2          A06X+015302Y+023069X0120Y0990R270 S2      
327P52V_HSC         PC60  -1          A06X+016436Y+023423X0400Y0500R090 S2      
327P52V_HSC         PU3   -18         A06X+014082Y+023699X0120Y0990R270 S2      
327P52V_HSC         PU5   -1          A06X+015912Y+030947X0118Y0945R270 S2      
327P52V_HSC         PU5   -2          A06X+015932Y+031577X0120Y0990R090 S2      
327P52V_HSC         PU5   -18         A06X+017152Y+030947X0120Y0990R090 S2      
327P52V_HSC         PC16  -1          A06X+014798Y+031223X0400Y0500R270 S2      
327P52V_HSC         PD6   -C          A06X+013048Y+032172X0950Y1300R270 S2      
327P52V_HSC         PU7   -18         A06X+006222Y+030947X0120Y0990R090 S2      
327P52V_HSC         PU7   -1          A06X+004982Y+030947X0118Y0945R270 S2      
327P52V_HSC         PU7   -2          A06X+005002Y+031577X0120Y0990R090 S2      
327P52V_HSC         PC62  -1          A06X+003868Y+031223X0400Y0500R270 S2      
327P52V_HSC         PD16  -C          A06X+002118Y+032172X0950Y1300R270 S2      
327P52V_HSC         PU1   -1          A06X+015912Y+103624X0118Y0945R270 S2      
327P52V_HSC         PU1   -2          A06X+015932Y+104254X0120Y0990R090 S2      
327P52V_HSC         PU1   -18         A06X+017152Y+103624X0120Y0990R090 S2      
327P52V_HSC         PC8   -1          A06X+014798Y+103900X0400Y0500R270 S2      
327P52V_HSC         PD3   -C          A06X+013048Y+104849X0950Y1300R270 S2      
327P52V_HSC         PU9   -18         A06X+006272Y+103624X0120Y0990R090 S2      
327P52V_HSC         PU9   -1          A06X+005032Y+103624X0118Y0945R270 S2      
327P52V_HSC         PU9   -2          A06X+005052Y+104254X0120Y0990R090 S2      
327P52V_HSC         PC64  -1          A06X+003906Y+103767X0400Y0500R270 S2      
327P52V_HSC         PD18  -C          A06X+002168Y+104849X0950Y1300R270 S2      
327P52V_HSC         GF1   -P1_P       A06X+011677Y+001968X1730Y2480     S2      
317P52V_HSC         VIA   -    MD0100PA00X+011452Y+004230X0200Y         S0      
317P52V_HSC         VIA   -    MD0100PA00X+011152Y+004230X0200Y         S0      
317P52V_HSC         VIA   -    MD0100PA00X+011452Y+003980X0200Y         S0      
317P52V_HSC         VIA   -    MD0100PA00X+011152Y+003980X0200Y         S0      
317P52V_HSC         VIA   -    MD0100PA00X+011452Y+004730X0200Y         S0      
317P52V_HSC         VIA   -    MD0100PA00X+011152Y+005230X0200Y         S0      
317P52V_HSC         VIA   -    MD0100PA00X+011452Y+005230X0200Y         S0      
317P52V_HSC         VIA   -    MD0100PA00X+011452Y+004980X0200Y         S0      
317P52V_HSC         VIA   -    MD0100PA00X+011152Y+004980X0200Y         S0      
317P52V_HSC         VIA   -    MD0100PA00X+011152Y+004730X0200Y         S0      
317P52V_HSC         VIA   -    MD0100PA00X+011452Y+004480X0200Y         S0      
317P52V_HSC         VIA   -    MD0100PA00X+011152Y+004480X0200Y         S0      
317P52V_HSC         VIA   -    MD0100PA00X+015936Y+103814X0200Y         S0      
317P52V_HSC         VIA   -    MD0100PA00X+016186Y+103814X0200Y         S0      
317P52V_HSC         VIA   -    MD0100PA00X+016186Y+104064X0200Y         S0      
317P52V_HSC         VIA   -    MD0100PA00X+015932Y+104064X0200Y         S0      
317P52V_HSC         VIA   -    MD0100PA00X+015678Y+104064X0200Y         S0      
317P52V_HSC         VIA   -    MD0100PA00X+015678Y+103814X0200Y         S0      
317P52V_HSC         VIA   -    MD0100PA00X+014948Y+104300X0200Y         S0      
317P52V_HSC         VIA   -    MD0100PA00X+014648Y+104300X0200Y         S0      
317P52V_HSC         VIA   -    MD0100PA00X+013038Y+103900X0200Y         S0      
317P52V_HSC         VIA   -    MD0100PA00X+013038Y+104200X0200Y         S0      
317P52V_HSC         VIA   -    MD0100PA00X+013038Y+105500X0200Y         S0      
317P52V_HSC         VIA   -    MD0100PA00X+013338Y+103900X0200Y         S0      
317P52V_HSC         VIA   -    MD0100PA00X+013338Y+104200X0200Y         S0      
317P52V_HSC         VIA   -    MD0100PA00X+013338Y+105500X0200Y         S0      
317P52V_HSC         VIA   -    M      A01X+012718Y+103900X0300Y         S1      
017P52V_HSC         VIA   -    M      A06X+012718Y+103900X0200Y         S1      
017P52V_HSC               -    MD0100PA00X+012718Y+103900                       
317P52V_HSC         VIA   -    MD0100PA00X+012718Y+104200X0200Y         S0      
317P52V_HSC         VIA   -    MD0100PA00X+012718Y+105500X0200Y         S0      
317P52V_HSC         VIA   -    MD0100PA00X+001349Y+104668X0200Y    R090 S0      
317P52V_HSC         VIA   -    MD0100PA00X+001349Y+105176X0200Y    R090 S0      
317P52V_HSC         VIA   -    MD0100PA00X+001349Y+104926X0200Y    R090 S0      
317P52V_HSC         VIA   -    M      A01X+001818Y+103890X0300Y         S1      
017P52V_HSC         VIA   -    M      A06X+001818Y+103890X0200Y         S1      
017P52V_HSC               -    MD0100PA00X+001818Y+103890                       
317P52V_HSC         VIA   -    MD0100PA00X+002138Y+103890X0200Y         S0      
317P52V_HSC         VIA   -    MD0100PA00X+002468Y+103880X0200Y         S0      
317P52V_HSC         VIA   -    MD0100PA00X+002138Y+104190X0200Y         S0      
317P52V_HSC         VIA   -    MD0100PA00X+001818Y+104190X0200Y         S0      
317P52V_HSC         VIA   -    MD0100PA00X+002468Y+104180X0200Y         S0      
317P52V_HSC         VIA   -    MD0100PA00X+004798Y+103814X0200Y         S0      
317P52V_HSC         VIA   -    MD0100PA00X+004798Y+104064X0200Y         S0      
317P52V_HSC         VIA   -    MD0100PA00X+005052Y+104064X0200Y         S0      
317P52V_HSC         VIA   -    MD0100PA00X+005306Y+104064X0200Y         S0      
317P52V_HSC         VIA   -    MD0100PA00X+005306Y+103814X0200Y         S0      
317P52V_HSC         VIA   -    MD0100PA00X+005056Y+103814X0200Y         S0      
317P52V_HSC         VIA   -    MD0100PA00X+003758Y+104130X0200Y         S0      
317P52V_HSC         VIA   -    MD0100PA00X+004058Y+104130X0200Y         S0      
317P52V_HSC         VIA   -    MD0100PA00X+018376Y+096910X0200Y    R180 S0      
317P52V_HSC         VIA   -    MD0100PA00X+018666Y+096900X0200Y    R180 S0      
317P52V_HSC         VIA   -    MD0100PA00X+018066Y+096900X0200Y    R180 S0      
317P52V_HSC         VIA   -    MD0100PA00X+016486Y+096180X0200Y    R180 S0      
317P52V_HSC         VIA   -    MD0100PA00X+016786Y+096180X0200Y    R180 S0      
317P52V_HSC         VIA   -    MD0100PA00X+015616Y+096251X0200Y    R180 S0      
317P52V_HSC         VIA   -    MD0100PA00X+015616Y+096501X0200Y    R180 S0      
317P52V_HSC         VIA   -    MD0100PA00X+015358Y+096501X0200Y    R180 S0      
317P52V_HSC         VIA   -    MD0100PA00X+015108Y+096501X0200Y    R180 S0      
317P52V_HSC         VIA   -    MD0100PA00X+015108Y+096251X0200Y    R180 S0      
317P52V_HSC         VIA   -    MD0100PA00X+015362Y+096251X0200Y    R180 S0      
317P52V_HSC         VIA   -    MD0100PA00X+018376Y+095300X0200Y    R180 S0      
317P52V_HSC         VIA   -    MD0100PA00X+018376Y+095620X0200Y    R180 S0      
317P52V_HSC         VIA   -    MD0100PA00X+018066Y+095290X0200Y    R180 S0      
317P52V_HSC         VIA   -    MD0100PA00X+018666Y+095290X0200Y    R180 S0      
317P52V_HSC         VIA   -    MD0100PA00X+018666Y+095610X0200Y    R180 S0      
317P52V_HSC         VIA   -    MD0100PA00X+018066Y+095610X0200Y    R180 S0      
317P52V_HSC         VIA   -    MD0100PA00X+002679Y+095936X0200Y    R180 S0      
317P52V_HSC         VIA   -    MD0100PA00X+002933Y+095936X0200Y    R180 S0      
317P52V_HSC         VIA   -    MD0100PA00X+003187Y+095936X0200Y    R180 S0      
317P52V_HSC         VIA   -    MD0100PA00X+003917Y+095840X0200Y    R180 S0      
317P52V_HSC         VIA   -    MD0100PA00X+004217Y+095840X0200Y    R180 S0      
317P52V_HSC         VIA   -    MD0100PA00X+004873Y+095701X0200Y    R180 S0      
317P52V_HSC         VIA   -    MD0100PA00X+004873Y+095951X0200Y    R180 S0      
317P52V_HSC         VIA   -    MD0100PA00X+002929Y+096186X0200Y    R180 S0      
317P52V_HSC         VIA   -    MD0100PA00X+002679Y+096186X0200Y    R180 S0      
317P52V_HSC         VIA   -    MD0100PA00X+003187Y+096186X0200Y    R180 S0      
317P52V_HSC         VIA   -    MD0100PA00X+004863Y+096211X0200Y    R180 S0      
317P52V_HSC         VIA   -    MD0100PA00X+004863Y+096461X0200Y    R180 S0      
317P52V_HSC         VIA   -    MD0100PA00X+004863Y+096721X0200Y    R180 S0      
317P52V_HSC         VIA   -    MD0100PA00X+004863Y+096971X0200Y    R180 S0      
317P52V_HSC         VIA   -    MD0100PA00X+004873Y+097481X0200Y    R180 S0      
317P52V_HSC         VIA   -    MD0100PA00X+004873Y+097231X0200Y    R180 S0      
317P52V_HSC         VIA   -    M      A01X+012748Y+031223X0300Y         S1      
017P52V_HSC         VIA   -    M      A06X+012748Y+031223X0200Y         S1      
017P52V_HSC               -    MD0100PA00X+012748Y+031223                       
317P52V_HSC         VIA   -    MD0100PA00X+012748Y+031523X0200Y         S0      
317P52V_HSC         VIA   -    MD0100PA00X+014948Y+031623X0200Y         S0      
317P52V_HSC         VIA   -    MD0100PA00X+014648Y+031623X0200Y         S0      
317P52V_HSC         VIA   -    MD0100PA00X+013048Y+031223X0200Y         S0      
317P52V_HSC         VIA   -    MD0100PA00X+013048Y+031523X0200Y         S0      
317P52V_HSC         VIA   -    MD0100PA00X+013348Y+031223X0200Y         S0      
317P52V_HSC         VIA   -    MD0100PA00X+013348Y+031523X0200Y         S0      
317P52V_HSC         VIA   -    MD0100PA00X+015936Y+031136X0200Y         S0      
317P52V_HSC         VIA   -    MD0100PA00X+016186Y+031136X0200Y         S0      
317P52V_HSC         VIA   -    MD0100PA00X+016186Y+031386X0200Y         S0      
317P52V_HSC         VIA   -    MD0100PA00X+015932Y+031386X0200Y         S0      
317P52V_HSC         VIA   -    MD0100PA00X+015678Y+031386X0200Y         S0      
317P52V_HSC         VIA   -    MD0100PA00X+015678Y+031136X0200Y         S0      
317P52V_HSC         VIA   -    MD0100PA00X+002418Y+031523X0200Y         S0      
317P52V_HSC         VIA   -    MD0100PA00X+002718Y+031523X0200Y         S0      
317P52V_HSC         VIA   -    M      A01X+002718Y+031223X0300Y         S1      
017P52V_HSC         VIA   -    M      A06X+002718Y+031223X0200Y         S1      
017P52V_HSC               -    MD0100PA00X+002718Y+031223                       
317P52V_HSC         VIA   -    MD0100PA00X+002418Y+031223X0200Y         S0      
317P52V_HSC         VIA   -    MD0100PA00X+001818Y+031523X0200Y         S0      
317P52V_HSC         VIA   -    MD0100PA00X+002118Y+031523X0200Y         S0      
317P52V_HSC         VIA   -    MD0100PA00X+002118Y+031223X0200Y         S0      
317P52V_HSC         VIA   -    M      A01X+001818Y+031223X0300Y         S1      
017P52V_HSC         VIA   -    M      A06X+001818Y+031223X0200Y         S1      
017P52V_HSC               -    MD0100PA00X+001818Y+031223                       
317P52V_HSC         VIA   -    MD0100PA00X+004018Y+031623X0200Y         S0      
317P52V_HSC         VIA   -    MD0100PA00X+003718Y+031623X0200Y         S0      
317P52V_HSC         VIA   -    MD0100PA00X+004748Y+031386X0200Y         S0      
317P52V_HSC         VIA   -    MD0100PA00X+004748Y+031136X0200Y         S0      
317P52V_HSC         VIA   -    MD0100PA00X+005006Y+031136X0200Y         S0      
317P52V_HSC         VIA   -    MD0100PA00X+005256Y+031136X0200Y         S0      
317P52V_HSC         VIA   -    MD0100PA00X+005256Y+031386X0200Y         S0      
317P52V_HSC         VIA   -    MD0100PA00X+005002Y+031386X0200Y         S0      
317P52V_HSC         VIA   -    MD0100PA00X+017966Y+024353X0200Y    R180 S0      
317P52V_HSC         VIA   -    MD0100PA00X+018266Y+024353X0200Y    R180 S0      
317P52V_HSC         VIA   -    MD0100PA00X+018566Y+024353X0200Y    R180 S0      
317P52V_HSC         VIA   -    MD0100PA00X+015556Y+023509X0200Y    R180 S0      
317P52V_HSC         VIA   -    MD0100PA00X+015298Y+023509X0200Y    R180 S0      
317P52V_HSC         VIA   -    MD0100PA00X+015048Y+023509X0200Y    R180 S0      
317P52V_HSC         VIA   -    MD0100PA00X+018536Y+022733X0200Y    R180 S0      
317P52V_HSC         VIA   -    MD0100PA00X+018236Y+022733X0200Y    R180 S0      
317P52V_HSC         VIA   -    M      A01X+018536Y+023033X0300Y    R180 S1      
017P52V_HSC         VIA   -    M      A06X+018536Y+023033X0200Y    R180 S1      
017P52V_HSC               -    MD0100PA00X+018536Y+023033                       
317P52V_HSC         VIA   -    MD0100PA00X+018236Y+023033X0200Y    R180 S0      
317P52V_HSC         VIA   -    MD0100PA00X+017936Y+022733X0200Y    R180 S0      
317P52V_HSC         VIA   -    MD0100PA00X+017936Y+023033X0200Y    R180 S0      
317P52V_HSC         VIA   -    MD0100PA00X+016302Y+023059X0200Y    R180 S0      
317P52V_HSC         VIA   -    MD0100PA00X+016556Y+023059X0200Y    R180 S0      
317P52V_HSC         VIA   -    MD0100PA00X+015556Y+023259X0200Y    R180 S0      
317P52V_HSC         VIA   -    MD0100PA00X+015048Y+023259X0200Y    R180 S0      
317P52V_HSC         VIA   -    MD0100PA00X+015302Y+023259X0200Y    R180 S0      
317P52V_HSC         VIA   -    MD0100PA00X+003187Y+023259X0200Y    R180 S0      
317P52V_HSC         VIA   -    MD0100PA00X+002933Y+023259X0200Y    R180 S0      
317P52V_HSC         VIA   -    MD0100PA00X+002679Y+023259X0200Y    R180 S0      
317P52V_HSC         VIA   -    MD0100PA00X+005446Y+023021X0200Y    R180 S0      
317P52V_HSC         VIA   -    M      A01X+004846Y+023021X0300Y    R180 S1      
017P52V_HSC         VIA   -    M      A06X+004846Y+023021X0200Y    R180 S1      
017P52V_HSC               -    MD0100PA00X+004846Y+023021                       
317P52V_HSC         VIA   -    MD0100PA00X+005146Y+023021X0200Y    R180 S0      
317P52V_HSC         VIA   -    MD0100PA00X+004217Y+023023X0200Y    R180 S0      
317P52V_HSC         VIA   -    MD0100PA00X+003917Y+023023X0200Y    R180 S0      
317P52V_HSC         VIA   -    MD0100PA00X+005448Y+023346X0200Y    R180 S0      
317P52V_HSC         VIA   -    MD0100PA00X+005148Y+023346X0200Y    R180 S0      
317P52V_HSC         VIA   -    MD0100PA00X+004848Y+023346X0200Y    R180 S0      
317P52V_HSC         VIA   -    MD0100PA00X+003187Y+023509X0200Y    R180 S0      
317P52V_HSC         VIA   -    MD0100PA00X+002679Y+023509X0200Y    R180 S0      
317P52V_HSC         VIA   -    MD0100PA00X+002929Y+023509X0200Y    R180 S0      
317P52V_HSC         VIA   -    MD0100PA00X+005697Y+024623X0200Y    R180 S0      
317P52V_HSC         VIA   -    MD0100PA00X+005397Y+024623X0200Y    R180 S0      
317P52V_HSC         VIA   -    MD0100PA00X+005097Y+024623X0200Y    R180 S0      
327FAN_0_SS         PC5   -1          A06X+017750Y+101958X0198Y0197R090 S2      
317FAN_0_SS         VIA   -    M      A01X+017386Y+102550X0300Y         S1      
017FAN_0_SS         VIA   -    M      A06X+017386Y+102550X0200Y         S1      
017FAN_0_SS               -    MD0100PA00X+017386Y+102550                       
327FAN_0_SS         PU1   -21         A06X+017093Y+103171X0070Y0360R180 S2      
327FAN_0_CS         PR6   -1          A06X+018550Y+101958X0198Y0197R090 S2      
317FAN_0_CS         VIA   -    M      A01X+018206Y+102252X0300Y         S1      
017FAN_0_CS         VIA   -    M      A06X+018206Y+102252X0200Y         S1      
017FAN_0_CS               -    MD0100PA00X+018206Y+102252                       
327FAN_0_CS         PU1   -19         A06X+017408Y+103171X0276Y0354R180 S2      
327m0132            R518  -1   M      A01X+016392Y+071300X0198Y0197     S1      
327m0132            R519  -2          A01X+017592Y+071300X0198Y0197R180 S1      
317m0132            VIA   -    M      A01X+017158Y+071650X0200Y         S2      
017m0132            VIA   -    M      A06X+017158Y+071650X0260Y         S2      
017m0132                  -    MD0100PA00X+017158Y+071650                       
327m0132            U390  -11         A01X+015400Y+071500X0140Y0590R270 S1      
317FAN_1_ON         VIA   -    M      A01X+016434Y+100248X0300Y    R180 S1      
017FAN_1_ON         VIA   -    M      A06X+016434Y+100248X0200Y    R180 S1      
017FAN_1_ON               -    MD0100PA00X+016434Y+100248                       
327FAN_1_ON         R5419 -1          A01X+015641Y+099865X0198Y0197     S1      
327FAN_1_ON         PU4   -26         A06X+014928Y+097144X0070Y0360     S2      
317FAN_1_ON         VIA   -    MD0100PA00X+014966Y+097497X0200Y    R180 S0      
327m0133            R5418 -1          A01X+014606Y+099265X0198Y0197R180 S1      
317m0133            VIA   -    M      A01X+014448Y+099565X0200Y    R180 S2      
017m0133            VIA   -    M      A06X+014448Y+099565X0260Y    R180 S2      
017m0133                  -    MD0100PA00X+014448Y+099565                       
327m0133            U379  -1          A06X+015119Y+099309X0130Y0460R270 S2      
327FAN_0_IMON       PR10  -2          A06X+018150Y+101958X0198Y0197R270 S2      
327FAN_0_IMON       VIA   -    M      A06X+017836Y+102406X0260Y         S2      
327FAN_0_IMON       PU1   -20         A06X+017251Y+103171X0070Y0360R180 S2      
317FAN_1_PRESENT    VIA   -    M      A01X+011750Y+085758X0200Y         S2      
017FAN_1_PRESENT    VIA   -    M      A06X+011750Y+085758X0260Y         S2      
017FAN_1_PRESENT          -    MD0100PA00X+011750Y+085758                       
327FAN_1_PRESENT    U406  -G          A01X+016685Y+085856X0240Y0320R270 S1      
327FAN_1_PRESENT    R5651 -1   M      A01X+016100Y+085758X0198Y0197R270 S1      
327FAN_1_PRESENT    R5418 -2          A01X+014291Y+099265X0198Y0197R180 S1      
317FAN_1_PRESENT    VIA   -    MD0100PA00X+013944Y+098950X0200Y    R180 S0      
327FAN_1_PRESENT    U395  -4          A06X+013944Y+099261X0240Y0240R090 S2      
327FAN_0_CLREF      VIA   -    M      A06X+016621Y+102508X0260Y         S2      
327FAN_0_CLREF      PC3118-2          A06X+016950Y+101958X0198Y0197R270 S2      
327FAN_0_CLREF      PU1   -24         A06X+016621Y+103171X0070Y0360R180 S2      
327FAN_0_CLREF      PR9   -1   M      A06X+016550Y+101958X0198Y0197R090 S2      
327m0134            R5382 -2          A01X+005492Y+116850X0180Y0200     S1      
327m0134            VIA   -    M      A01X+004976Y+117506X0300Y         S1      
317m0134            J8    -12   D0380PA00X+003425Y+117839X0540Y    R270 S3      
327m0134            D257  -C   M      A01X+005483Y+117350X0220Y0240     S1      
327FAN_0_TEMP       PR8   -1          A06X+015142Y+101954X0198Y0197R090 S2      
317FAN_0_TEMP       VIA   -    M      A01X+014950Y+102300X0300Y         S1      
017FAN_0_TEMP       VIA   -    M      A06X+014950Y+102300X0200Y         S1      
017FAN_0_TEMP             -    MD0100PA00X+014950Y+102300                       
327FAN_0_TEMP       PU1   -29         A06X+015833Y+103171X0070Y0360R180 S2      
327FAN_0_TEMP       PC2118-1   M      A06X+014750Y+101958X0198Y0197R090 S2      
327m0135            R4966 -1   M      A01X+016392Y+074700X0198Y0197     S1      
327m0135            R4967 -2          A01X+017592Y+074700X0198Y0197R180 S1      
317m0135            VIA   -    M      A01X+017200Y+075150X0300Y         S1      
017m0135            VIA   -    M      A06X+017200Y+075150X0200Y         S1      
017m0135                  -    MD0100PA00X+017200Y+075150                       
327m0135            U389  -13         A01X+015450Y+075112X0140Y0590R270 S1      
327m0136            R5380 -2          A01X+005492Y+117850X0180Y0200     S1      
327m0136            VIA   -    M      A01X+004650Y+118400X0300Y         S1      
317m0136            J8    -14   D0380PA00X+003425Y+118626X0540Y    R270 S3      
327m0136            D258  -C   M      A01X+005483Y+118400X0220Y0240     S1      
327FAN_0_MODE       PR5   -2          A01X+016808Y+102150X0198Y0197     S1      
327FAN_0_MODE       PR7   -1   M      A01X+016808Y+102550X0198Y0197R180 S1      
317FAN_0_MODE       VIA   -    M      A01X+015315Y+102843X0300Y         S1      
017FAN_0_MODE       VIA   -    M      A06X+015315Y+102843X0200Y         S1      
017FAN_0_MODE             -    MD0100PA00X+015315Y+102843                       
327FAN_0_MODE       PU1   -30         A06X+015676Y+103171X0276Y0354R180 S2      
327FAN_0_P3V_R      PC3   -1          A06X+015950Y+101958X0198Y0197R090 S2      
317FAN_0_P3V_R      VIA   -    M      A01X+015950Y+102300X0300Y         S1      
017FAN_0_P3V_R      VIA   -    M      A06X+015950Y+102300X0200Y         S1      
017FAN_0_P3V_R            -    MD0100PA00X+015950Y+102300                       
327FAN_0_P3V_R      PU1   -27         A06X+016148Y+103171X0070Y0360R180 S2      
327FAN_0_P3V_R      PR1   -2   M      A01X+016492Y+101750X0198Y0197R180 S1      
327FAN_0_P3V_R      PR5   -1          A01X+016492Y+102150X0198Y0197     S1      
327FAN_0_P5V        PC4   -1          A06X+015542Y+101954X0198Y0197R090 S2      
327FAN_0_P5V        VIA   -    M      A06X+015686Y+102450X0260Y         S2      
327FAN_0_P5V        PU1   -28         A06X+015991Y+103171X0070Y0360R180 S2      
327PCA9555_MB0_A2   R2356 -2   M      A01X+001658Y+071900X0198Y0197     S1      
327PCA9555_MB0_A2   R2362 -1          A01X+001658Y+071500X0198Y0197R180 S1      
327PCA9555_MB0_A2   VIA   -    M      A01X+002200Y+071800X0300Y         S1      
327PCA9555_MB0_A2   U7    -3          A01X+002900Y+071746X0140Y0590R270 S1      
327FAN_0_FAULT      PR3   -2          A01X+017200Y+102058X0180Y0200R270 S1      
327FAN_0_FAULT      VIA   -    M      A01X+017702Y+101632X0300Y         S1      
317FAN_0_FAULT      VIA   -    MD0100PA00X+017093Y+102443X0200Y         S0      
327FAN_0_FAULT      PU1   -22         A06X+016936Y+103171X0070Y0360R180 S2      
327m0137            R520  -1   M      A01X+016392Y+072000X0198Y0197     S1      
327m0137            R521  -2          A01X+017592Y+072000X0198Y0197R180 S1      
327m0137            VIA   -    M      A01X+017109Y+072484X0300Y         S1      
327m0137            U390  -13         A01X+015400Y+072012X0140Y0590R270 S1      
327m0138            R5404 -2          A01X+014450Y+042308X0180Y0200R270 S1      
327m0138            VIA   -    M      A01X+015569Y+041873X0300Y         S1      
317m0138            J3    -14   D0380PA00X+016929Y+042012X0540Y    R090 S3      
327m0138            D276  -C   M      A01X+014867Y+041373X0220Y0240R180 S1      
327RST_SMB_PDB_N    GF1   -S1         A06X+009799Y+001713X0320Y1970     S2      
317RST_SMB_PDB_N    VIA   -    MD0100PA00X+008440Y+006420X0200Y         S0      
327RST_SMB_PDB_N    VIA   -    M      A01X+006171Y+055900X0300Y         S1      
327RST_SMB_PDB_N    R5645 -1          A01X+008000Y+056492X0198Y0197R090 S1      
327RST_SMB_PDB_N    R572  -1   M      A01X+008000Y+055908X0198Y0197R270 S1      
317RST_SMB_PDB_N    VIA   -    MD0100PA00X+002890Y+055690X0200Y         S0      
327FAN_0_FAULT_R    PR3   -1          A01X+017200Y+101742X0180Y0200R270 S1      
327FAN_0_FAULT_R    PR1   -1          A01X+016808Y+101750X0198Y0197R180 S1      
327m0139            R5410 -2          A01X+014500Y+043608X0180Y0200R270 S1      
327m0139            VIA   -    M      A01X+015531Y+043507X0300Y         S1      
327m0139            VIA   -    M      A01X+015560Y+042693X0300Y         S1      
317m0139            J3    -12   D0380PA00X+016929Y+042799X0540Y    R090 S3      
327m0139            D275  -C   M      A01X+014867Y+042800X0220Y0240R180 S1      
327PCA9555_MB0_A1   R2361 -2          A01X+001658Y+072300X0198Y0197     S1      
327PCA9555_MB0_A1   R2355 -1   M      A01X+001658Y+072700X0198Y0197R180 S1      
327PCA9555_MB0_A1   VIA   -    M      A01X+002150Y+072700X0300Y         S1      
327PCA9555_MB0_A1   U7    -2          A01X+002900Y+072002X0140Y0590R270 S1      
317FAN_0_ON         VIA   -    M      A01X+014723Y+100430X0200Y         S2      
017FAN_0_ON         VIA   -    M      A06X+014723Y+100430X0260Y         S2      
017FAN_0_ON               -    MD0100PA00X+014723Y+100430                       
327FAN_0_ON         R5417 -1          A01X+015593Y+100450X0198Y0197R180 S1      
327FAN_0_ON         PU1   -26         A06X+016306Y+103171X0070Y0360R180 S2      
317FAN_0_ON         VIA   -    MD0100PA00X+016188Y+102605X0200Y         S0      
327m0140            R4964 -1   M      A01X+016392Y+074000X0198Y0197     S1      
327m0140            R4965 -2          A01X+017592Y+074000X0198Y0197R180 S1      
317m0140            VIA   -    M      A01X+017150Y+074350X0200Y         S2      
017m0140            VIA   -    M      A06X+017150Y+074350X0260Y         S2      
017m0140                  -    MD0100PA00X+017150Y+074350                       
327m0140            U389  -11         A01X+015450Y+074600X0140Y0590R270 S1      
327PCA9555_MB0_A0   R2354 -1          A01X+008042Y+071500X0198Y0197     S1      
327PCA9555_MB0_A0   R2360 -2   M      A01X+007092Y+071500X0198Y0197R180 S1      
327PCA9555_MB0_A0   VIA   -    M      A01X+006587Y+071500X0300Y         S1      
327PCA9555_MB0_A0   U7    -21         A01X+005200Y+071490X0140Y0590R270 S1      
327m0141            R5374 -2          A01X+005492Y+080500X0180Y0200     S1      
327m0141            VIA   -    M      A01X+004690Y+080650X0300Y         S1      
317m0141            J7    -12   D0380PA00X+003425Y+081500X0540Y    R270 S3      
327m0141            D251  -C          A01X+005483Y+081000X0220Y0240     S1      
327m0142            R5372 -2          A01X+005492Y+081600X0180Y0200     S1      
327m0142            VIA   -    M      A01X+004650Y+082061X0300Y         S1      
317m0142            J7    -14   D0380PA00X+003425Y+082287X0540Y    R270 S3      
327m0142            D252  -C   M      A01X+005483Y+082061X0220Y0240     S1      
327FAN_5_FAULT_R    PR56  -1          A01X+005650Y+028942X0180Y0200R270 S1      
327FAN_5_FAULT_R    VIA   -    M      A01X+005196Y+028383X0300Y         S1      
327FAN_5_FAULT_R    PR55  -1          A01X+005258Y+028900X0198Y0197R180 S1      
327FAN_5_FAULT      PR56  -2          A01X+005650Y+029258X0180Y0200R270 S1      
317FAN_5_FAULT      VIA   -    M      A01X+006142Y+029931X0200Y         S2      
017FAN_5_FAULT      VIA   -    M      A06X+006142Y+029931X0260Y         S2      
017FAN_5_FAULT            -    MD0100PA00X+006142Y+029931                       
327FAN_5_FAULT      PU7   -22         A06X+006006Y+030494X0070Y0360R180 S2      
317FAN_5_TEMP       VIA   -    M      A01X+004050Y+029550X0300Y         S1      
017FAN_5_TEMP       VIA   -    M      A06X+004050Y+029550X0200Y         S1      
017FAN_5_TEMP             -    MD0100PA00X+004050Y+029550                       
327FAN_5_TEMP       PU7   -29         A06X+004904Y+030494X0070Y0360R180 S2      
327FAN_5_TEMP       PR60  -1   M      A06X+004112Y+029277X0198Y0197R090 S2      
327FAN_5_TEMP       PC2123-1          A06X+003706Y+029277X0198Y0197R090 S2      
327FAN_5_SS         PC46  -1          A06X+006806Y+029280X0198Y0197R090 S2      
327FAN_5_SS         PU7   -21         A06X+006164Y+030494X0070Y0360R180 S2      
317FAN_5_SS         VIA   -    M      A01X+006456Y+029845X0300Y         S1      
017FAN_5_SS         VIA   -    M      A06X+006456Y+029845X0200Y         S1      
017FAN_5_SS               -    MD0100PA00X+006456Y+029845                       
317FAN_5_CLREF      VIA   -    M      A01X+005743Y+029852X0300Y         S1      
017FAN_5_CLREF      VIA   -    M      A06X+005743Y+029852X0200Y         S1      
017FAN_5_CLREF            -    MD0100PA00X+005743Y+029852                       
327FAN_5_CLREF      PC3123-2          A06X+005550Y+029280X0198Y0197R270 S2      
327FAN_5_CLREF      PR61  -1   M      A06X+005950Y+029280X0198Y0197R090 S2      
327FAN_5_CLREF      PU7   -24         A06X+005691Y+030494X0070Y0360R180 S2      
317FAN_5_P3V_R      VIA   -    M      A01X+005200Y+029853X0300Y         S1      
017FAN_5_P3V_R      VIA   -    M      A06X+005200Y+029853X0200Y         S1      
017FAN_5_P3V_R            -    MD0100PA00X+005200Y+029853                       
327FAN_5_P3V_R      PC44  -1          A06X+004900Y+029278X0198Y0197R090 S2      
327FAN_5_P3V_R      PU7   -27         A06X+005219Y+030494X0070Y0360R180 S2      
327FAN_5_P3V_R      PR57  -1   M      A01X+004550Y+028942X0198Y0197R090 S1      
327FAN_5_P3V_R      PR55  -2          A01X+004942Y+028900X0198Y0197R180 S1      
327FAN_5_P5V        PC45  -1          A06X+004512Y+029277X0198Y0197R090 S2      
327FAN_5_P5V        PU7   -28         A06X+005061Y+030494X0070Y0360R180 S2      
327FAN_5_P5V        VIA   -    M      A06X+004756Y+029773X0260Y         S2      
327m0143            R5366 -2          A01X+005950Y+043492X0180Y0200R090 S1      
327m0143            VIA   -    M      A01X+004650Y+045161X0300Y         S1      
317m0143            J6    -12   D0380PA00X+003425Y+045161X0540Y    R270 S3      
327m0143            D245  -C   M      A01X+005483Y+044373X0220Y0240     S1      
327m0144            VIA   -    M      A01X+004920Y+045723X0300Y         S1      
327m0144            R5364 -2          A01X+005950Y+044892X0180Y0200R090 S1      
317m0144            J6    -14   D0380PA00X+003425Y+045949X0540Y    R270 S3      
327m0144            D246  -C   M      A01X+005483Y+045723X0220Y0240     S1      
327FAN_5_CS         PR58  -1          A06X+007706Y+029280X0180Y0200R270 S2      
317FAN_5_CS         VIA   -    M      A01X+007169Y+030200X0300Y         S1      
017FAN_5_CS         VIA   -    M      A06X+007169Y+030200X0200Y         S1      
017FAN_5_CS               -    MD0100PA00X+007169Y+030200                       
327FAN_5_CS         PU7   -19         A06X+006478Y+030494X0276Y0354R180 S2      
327FAN_5_TIMER      PC47  -1          A06X+006350Y+029280X0198Y0197R090 S2      
327FAN_5_TIMER      PU7   -23         A06X+005848Y+030494X0070Y0360R180 S2      
327FAN_5_IMON       PR62  -2          A06X+007256Y+029280X0180Y0200R090 S2      
327FAN_5_IMON       PU7   -20         A06X+006321Y+030494X0070Y0360R180 S2      
327FAN_5_IMON       VIA   -    M      A06X+007000Y+029850X0260Y         S2      
327FAN_5_MODE       VIA   -    M      A01X+004550Y+029835X0300Y         S1      
327FAN_5_MODE       PR57  -2   M      A01X+004550Y+029258X0198Y0197R090 S1      
327FAN_5_MODE       PR59  -1          A01X+004942Y+029300X0198Y0197     S1      
327FAN_5_MODE       PU7   -30         A06X+004746Y+030494X0276Y0354R180 S2      
317FAN_5_MODE       VIA   -    MD0100PA00X+004450Y+030150X0200Y         S0      
327m0145            VIA   -    M      A01X+005090Y+119015X0300Y         S1      
317m0145            J8    -13   D0380PA00X+002638Y+118626X0540Y    R270 S3      
327m0145            D259  -C          A01X+005600Y+119733X0220Y0240R090 S1      
327m0145            D144  -2   M      A01X+005624Y+119065X0320Y0340R180 S1      
317m0146            J1    -12   D0380PA00X+016929Y+115476X0540Y    R090 S3      
327m0146            VIA   -    M      A01X+015700Y+115500X0300Y         S1      
327m0146            R5414 -2   M      A01X+014858Y+115600X0180Y0200R180 S1      
327m0146            D263  -C          A01X+014867Y+115100X0220Y0240R180 S1      
327FAN_7_PWM_OL_R   VIA   -    M      A01X+004641Y+113671X0300Y         S1      
317FAN_7_PWM_OL_R   J8    -2    D0380PA00X+003425Y+113902X0540Y    R270 S3      
327FAN_7_PWM_OL_R   R5238 -2   M      A01X+005447Y+112865X0198Y0197R180 S1      
327FAN_7_PWM_OL_R   C2056 -1   M      A01X+006297Y+112865X0198Y0197     S1      
327FAN_7_PWM_OL_R   D261  -C          A01X+007187Y+112865X0220Y0240     S1      
327m0147            VIA   -    M      A01X+005390Y+114277X0300Y         S1      
317m0147            J8    -1    D0380PA00X+002638Y+113902X0540Y0540R270 S3      
327m0147            D260  -C   M      A01X+005887Y+114265X0220Y0240     S1      
327m0147            D142  -2          A01X+005624Y+113615X0320Y0340R180 S1      
327FAN_7_PWM_IL_R   VIA   -    M      A01X+004650Y+114765X0300Y         S1      
317FAN_7_PWM_IL_R   J8    -3    D0380PA00X+002638Y+114689X0540Y    R270 S3      
327FAN_7_PWM_IL_R   R5241 -1   M      A01X+005497Y+114765X0198Y0197     S1      
327FAN_7_PWM_IL_R   C2057 -1          A01X+006347Y+114765X0198Y0197     S1      
327FAN_7_PWM_IL_R   D262  -C          A01X+007183Y+114750X0220Y0240     S1      
317PU_U8_PIN2       VIA   -    M      A01X+012340Y+066910X0200Y         S2      
017PU_U8_PIN2       VIA   -    M      A06X+012340Y+066910X0260Y         S2      
017PU_U8_PIN2             -    MD0100PA00X+012340Y+066910                       
327PU_U8_PIN2       R5093 -1          A01X+011558Y+066750X0198Y0197R180 S1      
327PU_U8_PIN2       U8    -21         A01X+013150Y+066910X0140Y0590R090 S1      
327FAN_3_TACH_OL    R5433 -1          A06X+015942Y+049850X0180Y0200     S2      
327FAN_3_TACH_OL    R5584 -1          A01X+015050Y+048700X0180Y0200R180 S1      
327FAN_3_TACH_OL    R5608 -1   M      A01X+015050Y+048700X0180Y0200     S1      
317FAN_3_TACH_OL    VIA   -    MD0100PA00X+015050Y+048950X0200Y         S0      
327FAN_3_TACH_OL    R5327 -2          A01X+012992Y+006500X0180Y0200     S1      
317FAN_3_TACH_OL    VIA   -    M      A01X+011592Y+007565X0200Y         S2      
017FAN_3_TACH_OL    VIA   -    M      A06X+011592Y+007565X0260Y         S2      
017FAN_3_TACH_OL          -    MD0100PA00X+011592Y+007565                       
327FAN_6_PWM_IL_R   VIA   -    M      A01X+004650Y+078376X0300Y         S1      
317FAN_6_PWM_IL_R   J7    -3    D0380PA00X+002638Y+078350X0540Y    R270 S3      
327FAN_6_PWM_IL_R   R5221 -1   M      A01X+005497Y+078376X0198Y0197     S1      
327FAN_6_PWM_IL_R   C2045 -1          A01X+006347Y+078376X0198Y0197     S1      
327FAN_6_PWM_IL_R   D256  -C          A01X+007183Y+078361X0220Y0240     S1      
327FAN_2_TACH_OL    R5331 -2          A01X+012942Y+040373X0180Y0200     S1      
327FAN_2_TACH_OL    R5431 -1          A06X+015942Y+050300X0180Y0200     S2      
327FAN_2_TACH_OL    R5582 -1          A01X+015058Y+049700X0180Y0200R180 S1      
327FAN_2_TACH_OL    R5606 -1   M      A01X+015058Y+049700X0180Y0200     S1      
317FAN_2_TACH_OL    VIA   -    MD0100PA00X+015058Y+049950X0200Y         S0      
317FAN_2_TACH_OL    VIA   -    M      A01X+011850Y+040350X0300Y         S1      
017FAN_2_TACH_OL    VIA   -    M      A06X+011850Y+040350X0200Y         S1      
017FAN_2_TACH_OL          -    MD0100PA00X+011850Y+040350                       
317FAN_7_ON         VIA   -    M      A01X+005185Y+101225X0300Y         S1      
017FAN_7_ON         VIA   -    M      A06X+005185Y+101225X0200Y         S1      
017FAN_7_ON               -    MD0100PA00X+005185Y+101225                       
327FAN_7_ON         R5425 -1          A01X+004714Y+100450X0198Y0197R180 S1      
317FAN_7_ON         VIA   -    MD0100PA00X+004849Y+100686X0200Y         S0      
327FAN_7_ON         PU9   -26         A06X+005426Y+103171X0070Y0360R180 S2      
317FAN_7_ON         VIA   -    MD0100PA00X+005300Y+102600X0200Y         S0      
327FAN_6_PWM_OL_R   VIA   -    M      A01X+004980Y+076476X0300Y         S1      
317FAN_6_PWM_OL_R   J7    -2    D0380PA00X+003425Y+077563X0540Y    R270 S3      
327FAN_6_PWM_OL_R   R5218 -2   M      A01X+005447Y+076476X0198Y0197R180 S1      
327FAN_6_PWM_OL_R   C2044 -1   M      A01X+006297Y+076476X0198Y0197     S1      
327FAN_6_PWM_OL_R   D255  -C          A01X+007187Y+076476X0220Y0240     S1      
327m0148            R5358 -2          A01X+005950Y+008942X0180Y0200R090 S1      
317m0148            J5    -12   D0380PA00X+003425Y+008823X0540Y    R270 S3      
327m0148            VIA   -    M      A01X+005000Y+009750X0300Y         S1      
327m0148            D239  -C   M      A01X+005533Y+009750X0220Y0240     S1      
327m0149            VIA   -    M      A01X+005090Y+082700X0300Y         S1      
317m0149            J7    -13   D0380PA00X+002638Y+082287X0540Y    R270 S3      
327m0149            D253  -C          A01X+005887Y+083376X0220Y0240     S1      
327m0149            D140  -2   M      A01X+005624Y+082726X0320Y0340R180 S1      
327m0150            R5349 -2          A01X+005950Y+010442X0180Y0200R090 S1      
327m0150            D240  -C   M      A01X+005533Y+011369X0220Y0240     S1      
317m0150            J5    -14   D0380PA00X+003425Y+009610X0540Y    R270 S3      
327m0150            VIA   -    M      A01X+004950Y+010960X0300Y         S1      
327m0151            R5424 -1          A01X+005749Y+101050X0198Y0197     S1      
327m0151            U385  -1          A06X+005235Y+101006X0130Y0460R090 S2      
317m0151            VIA   -    M      A01X+005927Y+100779X0200Y         S2      
017m0151            VIA   -    M      A06X+005927Y+100779X0260Y         S2      
017m0151                  -    MD0100PA00X+005927Y+100779                       
327m0152            VIA   -    M      A01X+004940Y+077226X0300Y         S1      
317m0152            J7    -1    D0380PA00X+002638Y+077563X0540Y0540R270 S3      
327m0152            D254  -C          A01X+005533Y+077850X0220Y0240     S1      
327m0152            D138  -2   M      A01X+005624Y+077226X0320Y0340R180 S1      
327FAN_7_PRESENT    R5424 -2          A01X+006064Y+101050X0198Y0197     S1      
317FAN_7_PRESENT    VIA   -    M      A01X+007200Y+101350X0300Y         S1      
017FAN_7_PRESENT    VIA   -    M      A06X+007200Y+101350X0200Y         S1      
017FAN_7_PRESENT          -    MD0100PA00X+007200Y+101350                       
327FAN_7_PRESENT    U398  -4          A06X+006411Y+101054X0240Y0240R270 S2      
317FAN_7_PRESENT    VIA   -    M      A01X+001950Y+123950X0200Y         S2      
017FAN_7_PRESENT    VIA   -    M      A06X+001950Y+123950X0260Y         S2      
017FAN_7_PRESENT          -    MD0100PA00X+001950Y+123950                       
327FAN_7_PRESENT    U412  -G          A01X+001806Y+123415X0240Y0320R180 S1      
327FAN_7_PRESENT    R5669 -1   M      A01X+001708Y+123950X0198Y0197R180 S1      
327FAN_5_PWM_OL_R   VIA   -    M      A01X+004980Y+040138X0300Y         S1      
317FAN_5_PWM_OL_R   J6    -2    D0380PA00X+003425Y+041224X0540Y    R270 S3      
327FAN_5_PWM_OL_R   R5198 -2   M      A01X+005447Y+040138X0198Y0197R180 S1      
327FAN_5_PWM_OL_R   C2032 -1   M      A01X+006297Y+040138X0198Y0197     S1      
327FAN_5_PWM_OL_R   D249  -C          A01X+007187Y+040138X0220Y0240     S1      
327FAN_0_TACH_OL    R5303 -2          A01X+013300Y+112892X0180Y0200R090 S1      
327FAN_0_TACH_OL    R5427 -1          A06X+015942Y+052100X0180Y0200     S2      
327FAN_0_TACH_OL    R5576 -1          A01X+015058Y+052700X0180Y0200R180 S1      
327FAN_0_TACH_OL    R5600 -1   M      A01X+015058Y+052700X0180Y0200     S1      
317FAN_0_TACH_OL    VIA   -    MD0100PA00X+015058Y+052950X0200Y         S0      
317FAN_0_TACH_OL    VIA   -    M      A01X+013218Y+111732X0200Y         S2      
017FAN_0_TACH_OL    VIA   -    M      A06X+013218Y+111732X0260Y         S2      
017FAN_0_TACH_OL          -    MD0100PA00X+013218Y+111732                       
327FAN_6_ON         R5423 -1          A01X+003272Y+099550X0198Y0197     S1      
317FAN_6_ON         VIA   -    M      A01X+003052Y+100029X0300Y    R180 S1      
017FAN_6_ON         VIA   -    M      A06X+003052Y+100029X0200Y    R180 S1      
017FAN_6_ON               -    MD0100PA00X+003052Y+100029                       
327FAN_6_ON         PU8   -26         A06X+002559Y+096829X0070Y0360     S2      
317FAN_6_ON         VIA   -    MD0100PA00X+002699Y+097503X0200Y    R180 S0      
327m0153            VIA   -    M      A01X+004650Y+046338X0300Y         S1      
317m0153            J6    -13   D0380PA00X+002638Y+045949X0540Y    R270 S3      
327m0153            D136  -2   M      A01X+005624Y+046388X0320Y0340R180 S1      
327m0153            D247  -C          A01X+005887Y+047038X0220Y0240     S1      
327FAN_5_PWM_IL_R   VIA   -    M      A01X+004650Y+042387X0300Y         S1      
317FAN_5_PWM_IL_R   J6    -3    D0380PA00X+002638Y+042012X0540Y    R270 S3      
327FAN_5_PWM_IL_R   R5201 -1   M      A01X+005497Y+042038X0198Y0197     S1      
327FAN_5_PWM_IL_R   C2033 -1          A01X+006347Y+042038X0198Y0197     S1      
327FAN_5_PWM_IL_R   D250  -C          A01X+007183Y+042023X0220Y0240     S1      
327FAN_0_TACH_IL    R5302 -2          A01X+012842Y+118800X0180Y0200     S1      
327FAN_0_TACH_IL    R5426 -1          A06X+015942Y+053000X0180Y0200     S2      
327FAN_0_TACH_IL    R5574 -1          A01X+015058Y+053700X0180Y0200R180 S1      
327FAN_0_TACH_IL    R5598 -1   M      A01X+015058Y+053700X0180Y0200     S1      
317FAN_0_TACH_IL    VIA   -    MD0100PA00X+015058Y+053950X0200Y         S0      
317FAN_0_TACH_IL    VIA   -    M      A01X+011984Y+076166X0200Y         S2      
017FAN_0_TACH_IL    VIA   -    M      A06X+011984Y+076166X0260Y         S2      
017FAN_0_TACH_IL          -    MD0100PA00X+011984Y+076166                       
317FAN_0_TACH_IL    VIA   -    MD0100PA00X+010150Y+082427X0200Y         S0      
317FAN_0_TACH_IL    VIA   -    MD0100PA00X+012636Y+118595X0200Y         S0      
327m0154            VIA   -    M      A01X+004650Y+041600X0300Y         S1      
317m0154            J6    -1    D0380PA00X+002638Y+041224X0540Y0540R270 S3      
327m0154            D134  -2          A01X+005624Y+040888X0320Y0340R180 S1      
327m0154            D248  -C   M      A01X+005887Y+041538X0220Y0240     S1      
327m0155            D241  -C          A01X+005937Y+012684X0220Y0240     S1      
327m0155            D114  -2   M      A01X+005674Y+012034X0320Y0340R180 S1      
317m0155            J5    -13   D0380PA00X+002638Y+009610X0540Y    R270 S3      
327m0155            VIA   -    M      A01X+005140Y+012034X0300Y         S1      
327FAN_5_TACH_OL    R5315 -2          A01X+005842Y+047500X0180Y0200     S1      
327FAN_5_TACH_OL    R5437 -1          A06X+006792Y+051050X0180Y0200     S2      
327FAN_5_TACH_OL    R5590 -1          A01X+005692Y+050600X0180Y0200     S1      
327FAN_5_TACH_OL    R5614 -1   M      A01X+005692Y+050600X0180Y0200R180 S1      
317FAN_5_TACH_OL    VIA   -    MD0100PA00X+004969Y+047420X0200Y         S0      
317FAN_5_TACH_OL    VIA   -    M      A01X+005692Y+050850X0200Y         S2      
017FAN_5_TACH_OL    VIA   -    M      A06X+005692Y+050850X0260Y         S2      
017FAN_5_TACH_OL          -    MD0100PA00X+005692Y+050850                       
327m0156            R5422 -1          A01X+001700Y+099258X0198Y0197R270 S1      
317m0156            VIA   -    M      A01X+002301Y+099549X0300Y    R180 S1      
017m0156            VIA   -    M      A06X+002301Y+099549X0200Y    R180 S1      
017m0156                  -    MD0100PA00X+002301Y+099549                       
327m0156            U383  -1          A06X+002750Y+098994X0130Y0460R270 S2      
327FAN_4_PWM_OL_R   D243  -C          A01X+007187Y+005634X0220Y0240     S1      
327FAN_4_PWM_OL_R   C2014 -1   M      A01X+006454Y+005792X0198Y0197R270 S1      
317FAN_4_PWM_OL_R   J5    -2    D0380PA00X+003425Y+004886X0540Y    R270 S3      
327FAN_4_PWM_OL_R   VIA   -    M      A01X+004810Y+005634X0300Y         S1      
327FAN_4_PWM_OL_R   R5128 -2   M      A01X+005447Y+005634X0198Y0197R180 S1      
327m0157            R5416 -1          A01X+016628Y+101050X0198Y0197     S1      
317m0157            VIA   -    M      A01X+016786Y+100750X0200Y         S2      
017m0157            VIA   -    M      A06X+016786Y+100750X0260Y         S2      
017m0157                  -    MD0100PA00X+016786Y+100750                       
327m0157            U377  -1          A06X+016115Y+101006X0130Y0460R090 S2      
327m0158            D242  -C          A01X+005887Y+007034X0220Y0240     S1      
327m0158            D113  -2   M      A01X+005624Y+006384X0320Y0340R180 S1      
317m0158            J5    -1    D0380PA00X+002638Y+004886X0540Y0540R270 S3      
327m0158            VIA   -    M      A01X+005000Y+006384X0300Y         S1      
327FAN_4_PWM_IL_R   VIA   -    M      A01X+004831Y+006869X0300Y         S1      
327FAN_4_PWM_IL_R   D244  -C          A01X+007183Y+007519X0220Y0240     S1      
327FAN_4_PWM_IL_R   C2015 -1   M      A01X+006347Y+007534X0198Y0197     S1      
317FAN_4_PWM_IL_R   J5    -3    D0380PA00X+002638Y+005673X0540Y    R270 S3      
327FAN_4_PWM_IL_R   R5130 -1   M      A01X+005497Y+007534X0198Y0197     S1      
327P52V_FAN_EN      R4970 -2          A01X+010108Y+008155X0198Y0197     S1      
317P52V_FAN_EN      VIA   -    MD0100PA00X+011200Y+008870X0200Y         S0      
317P52V_FAN_EN      VIA   -    MD0100PA00X+014800Y+048300X0200Y         S0      
317P52V_FAN_EN      VIA   -    M      A01X+014190Y+064541X0200Y         S2      
017P52V_FAN_EN      VIA   -    M      A06X+014190Y+064541X0260Y         S2      
017P52V_FAN_EN            -    MD0100PA00X+014190Y+064541                       
327P52V_FAN_EN      R513  -2          A01X+012942Y+072850X0198Y0197R180 S1      
317P52V_FAN_EN      VIA   -    M      A01X+012806Y+072557X0200Y         S2      
017P52V_FAN_EN      VIA   -    M      A06X+012806Y+072557X0260Y         S2      
017P52V_FAN_EN            -    MD0100PA00X+012806Y+072557                       
327P52V_FAN_EN      R4959 -2          A01X+011792Y+075200X0198Y0197R180 S1      
317P52V_FAN_EN      VIA   -    MD0100PA00X+012154Y+074925X0200Y         S0      
327m0159            VIA   -    M      A01X+015678Y+008772X0300Y         S1      
327m0159            R5408 -2          A01X+014450Y+008542X0180Y0200R090 S1      
317m0159            J4    -12   D0380PA00X+016929Y+006461X0540Y    R090 S3      
327m0159            D281  -C   M      A01X+014867Y+009400X0220Y0240R180 S1      
327FAN_6_PRESENT    VIA   -    M      A06X+008000Y+098065X0260Y         S2      
317FAN_6_PRESENT    VIA   -    MD0100PA00X+009900Y+084800X0200Y         S0      
327FAN_6_PRESENT    U411  -G          A01X+008715Y+084594X0240Y0320R090 S1      
327FAN_6_PRESENT    R5668 -1   M      A01X+009250Y+084592X0198Y0197R090 S1      
327FAN_6_PRESENT    R5422 -2          A01X+001700Y+098942X0198Y0197R270 S1      
317FAN_6_PRESENT    VIA   -    MD0100PA00X+002000Y+098900X0200Y    R180 S0      
327FAN_6_PRESENT    U397  -4          A06X+001795Y+099146X0240Y0240R090 S2      
327FAN_6_TACH_OL    R5319 -2          A01X+006692Y+083400X0180Y0200     S1      
327FAN_6_TACH_OL    R5439 -1          A06X+006792Y+052400X0180Y0200     S2      
327FAN_6_TACH_OL    R5594 -1          A01X+005692Y+052600X0180Y0200     S1      
327FAN_6_TACH_OL    R5618 -1   M      A01X+005692Y+052600X0180Y0200R180 S1      
317FAN_6_TACH_OL    VIA   -    MD0100PA00X+004781Y+083301X0200Y         S0      
317FAN_6_TACH_OL    VIA   -    M      A01X+005692Y+052850X0200Y         S2      
017FAN_6_TACH_OL    VIA   -    M      A06X+005692Y+052850X0260Y         S2      
017FAN_6_TACH_OL          -    MD0100PA00X+005692Y+052850                       
327m0160            D282  -C   M      A01X+014867Y+007984X0220Y0240R180 S1      
317m0160            J4    -14   D0380PA00X+016929Y+005673X0540Y    R090 S3      
327m0160            VIA   -    M      A01X+015695Y+007605X0300Y         S1      
327m0160            R5406 -2          A01X+014450Y+007142X0180Y0200R090 S1      
317FAN_5_ON         VIA   -    M      A01X+004450Y+027277X0300Y         S1      
017FAN_5_ON         VIA   -    M      A06X+004450Y+027277X0200Y         S1      
017FAN_5_ON               -    MD0100PA00X+004450Y+027277                       
327FAN_5_ON         R5356 -1          A01X+004664Y+027773X0198Y0197R180 S1      
317FAN_5_ON         VIA   -    MD0100PA00X+005334Y+030133X0200Y         S0      
327FAN_5_ON         PU7   -26         A06X+005376Y+030494X0070Y0360R180 S2      
327FAN_7_TACH_OL    R5323 -2          A01X+007258Y+119650X0180Y0200R180 S1      
327FAN_7_TACH_OL    R5441 -1          A06X+006792Y+052850X0180Y0200     S2      
327FAN_7_TACH_OL    R5596 -1          A01X+005700Y+053600X0180Y0200     S1      
327FAN_7_TACH_OL    R5620 -1   M      A01X+005700Y+053600X0180Y0200R180 S1      
317FAN_7_TACH_OL    VIA   -    M      A01X+005700Y+053850X0200Y         S2      
017FAN_7_TACH_OL    VIA   -    M      A06X+005700Y+053850X0260Y         S2      
017FAN_7_TACH_OL          -    MD0100PA00X+005700Y+053850                       
317FAN_7_TACH_OL    VIA   -    MD0100PA00X+007500Y+119650X0200Y    R180 S0      
327m0161            R5355 -1          A01X+005699Y+028373X0198Y0197     S1      
317m0161            VIA   -    M      A01X+005856Y+028073X0200Y         S2      
017m0161            VIA   -    M      A06X+005856Y+028073X0260Y         S2      
017m0161                  -    MD0100PA00X+005856Y+028073                       
327m0161            U361  -1          A06X+005185Y+028329X0130Y0460R090 S2      
317FAN_5_PRESENT    VIA   -    M      A01X+008250Y+038950X0200Y         S2      
017FAN_5_PRESENT    VIA   -    M      A06X+008250Y+038950X0260Y         S2      
017FAN_5_PRESENT          -    MD0100PA00X+008250Y+038950                       
327FAN_5_PRESENT    R5355 -2          A01X+006014Y+028373X0198Y0197     S1      
317FAN_5_PRESENT    VIA   -    MD0100PA00X+006450Y+028700X0200Y         S0      
327FAN_5_PRESENT    U393  -4          A06X+006361Y+028377X0240Y0240R270 S2      
327FAN_5_PRESENT    R5667 -1   M      A01X+005550Y+038642X0198Y0197R090 S1      
327FAN_5_PRESENT    U410  -G          A01X+005015Y+038544X0240Y0320R090 S1      
317FAN_4_ON         VIA   -    MD0100PA00X+002604Y+024519X0200Y    R180 S0      
327FAN_4_ON         PU6   -26         A06X+002559Y+024152X0070Y0360     S2      
327FAN_4_ON         R5354 -1          A01X+003272Y+026873X0198Y0197     S1      
317FAN_4_ON         VIA   -    M      A01X+003272Y+027350X0300Y    R180 S1      
017FAN_4_ON         VIA   -    M      A06X+003272Y+027350X0200Y    R180 S1      
017FAN_4_ON               -    MD0100PA00X+003272Y+027350                       
327FAN_4_TACH_OL    R5311 -2          A01X+007150Y+012758X0180Y0200R270 S1      
317FAN_4_TACH_OL    VIA   -    M      A01X+007150Y+013000X0200Y    R180 S2      
017FAN_4_TACH_OL    VIA   -    M      A06X+007150Y+013000X0260Y    R180 S2      
017FAN_4_TACH_OL          -    MD0100PA00X+007150Y+013000                       
327FAN_4_TACH_OL    R5435 -1          A06X+006792Y+050600X0180Y0200     S2      
327FAN_4_TACH_OL    R5588 -1          A01X+005692Y+049550X0180Y0200     S1      
327FAN_4_TACH_OL    R5612 -1   M      A01X+005692Y+049550X0180Y0200R180 S1      
317FAN_4_TACH_OL    VIA   -    MD0100PA00X+005692Y+049800X0200Y         S0      
327m0162            R5353 -1          A01X+002237Y+026273X0198Y0197R180 S1      
317m0162            VIA   -    M      A01X+002150Y+026750X0300Y    R180 S1      
017m0162            VIA   -    M      A06X+002150Y+026750X0200Y    R180 S1      
017m0162                  -    MD0100PA00X+002150Y+026750                       
327m0162            U359  -1          A06X+002750Y+026317X0130Y0460R270 S2      
317FAN_4_PRESENT    VIA   -    M      A01X+008890Y+011930X0200Y         S2      
017FAN_4_PRESENT    VIA   -    M      A06X+008890Y+011930X0260Y         S2      
017FAN_4_PRESENT          -    MD0100PA00X+008890Y+011930                       
327FAN_4_PRESENT    VIA   -    M      A06X+008050Y+027342X0260Y         S2      
327FAN_4_PRESENT    R5353 -2          A01X+001922Y+026273X0198Y0197R180 S1      
317FAN_4_PRESENT    VIA   -    MD0100PA00X+001795Y+026750X0200Y    R180 S0      
327FAN_4_PRESENT    U392  -4          A06X+001795Y+026396X0240Y0240R090 S2      
327FAN_4_PRESENT    R5666 -1          A01X+010000Y+011942X0198Y0197R090 S1      
327FAN_4_PRESENT    U409  -G   M      A01X+009465Y+012094X0240Y0320R090 S1      
327FAN_4_PWM        U399  -2          A01X+011600Y+007874X0160Y0200     S1      
317FAN_4_PWM        VIA   -    MD0100PA00X+011848Y+008350X0200Y         S0      
327FAN_4_PWM        R5519 -2   M      A01X+011608Y+008350X0198Y0197     S1      
327FAN_4_PWM        R5585 -1          A01X+005700Y+048050X0180Y0200     S1      
327FAN_4_PWM        R5609 -1   M      A01X+005700Y+048050X0180Y0200R180 S1      
317FAN_4_PWM        VIA   -    MD0100PA00X+005700Y+048300X0200Y         S0      
317FAN_4_PWM        VIA   -    MD0100PA00X+005850Y+045450X0200Y         S0      
317FAN_4_PWM        VIA   -    M      A01X+010685Y+044160X0200Y         S2      
017FAN_4_PWM        VIA   -    M      A06X+010685Y+044160X0260Y         S2      
017FAN_4_PWM              -    MD0100PA00X+010685Y+044160                       
317FAN_3_ON         VIA   -    MD0100PA00X+015050Y+024700X0200Y    R180 S0      
317FAN_3_ON         VIA   -    M      A01X+014240Y+026980X0300Y         S1      
017FAN_3_ON         VIA   -    M      A06X+014240Y+026980X0200Y         S1      
017FAN_3_ON               -    MD0100PA00X+014240Y+026980                       
327FAN_3_ON         R506  -1          A01X+015641Y+026873X0198Y0197     S1      
327FAN_3_ON         PU3   -26         A06X+014928Y+024152X0070Y0360     S2      
327FAN_3_PWM_OL     U67   -2          A01X+010474Y+010356X0280Y0360R270 S1      
327FAN_3_PWM_OL     R5236 -1          A01X+014592Y+012684X0198Y0197     S1      
327FAN_3_PWM_OL     VIA   -    M      A01X+011042Y+011400X0300Y         S1      
327m0163            R503  -1          A01X+014606Y+026273X0198Y0197R180 S1      
317m0163            VIA   -    M      A01X+014448Y+026573X0200Y    R180 S2      
017m0163            VIA   -    M      A06X+014448Y+026573X0260Y    R180 S2      
017m0163                  -    MD0100PA00X+014448Y+026573                       
327m0163            U74   -1          A06X+015119Y+026317X0130Y0460R270 S2      
327FAN_2_PWM        R5579 -1          A01X+015058Y+051200X0180Y0200R180 S1      
327FAN_2_PWM        R5603 -1   M      A01X+015058Y+051200X0180Y0200     S1      
327FAN_2_PWM        R352  -2   M      A01X+008858Y+045050X0198Y0197     S1      
317FAN_2_PWM        VIA   -    M      A01X+010084Y+044650X0200Y         S2      
017FAN_2_PWM        VIA   -    M      A06X+010084Y+044650X0260Y         S2      
017FAN_2_PWM              -    MD0100PA00X+010084Y+044650                       
327FAN_2_PWM        U64   -2          A01X+008850Y+045526X0160Y0200R180 S1      
317FAN_2_PWM        VIA   -    MD0100PA00X+014150Y+051650X0200Y         S0      
327FAN_3_PRESENT    U408  -G          A01X+010835Y+013406X0240Y0320R270 S1      
327FAN_3_PRESENT    R5657 -1   M      A01X+010300Y+013308X0198Y0197R270 S1      
317FAN_3_PRESENT    VIA   -    MD0100PA00X+010300Y+013650X0200Y         S0      
327FAN_3_PRESENT    VIA   -    M      A06X+012345Y+023852X0260Y         S2      
327FAN_3_PRESENT    R503  -2          A01X+014291Y+026273X0198Y0197R180 S1      
317FAN_3_PRESENT    VIA   -    MD0100PA00X+013650Y+026100X0200Y    R180 S0      
327FAN_3_PRESENT    U391  -4          A06X+013944Y+026268X0240Y0240R090 S2      
317m0164            VIA   -    M      A01X+012450Y+066000X0200Y         S2      
017m0164            VIA   -    M      A06X+012450Y+066000X0260Y         S2      
017m0164                  -    MD0100PA00X+012450Y+066000                       
327m0164            R5469 -2          A01X+011558Y+065950X0198Y0197     S1      
327m0164            U8    -23         A01X+013150Y+066398X0140Y0590R090 S1      
327FAN_2_PWM_IL     R5220 -2          A01X+014542Y+045173X0198Y0197R180 S1      
327FAN_2_PWM_IL     VIA   -    M      A01X+012700Y+044600X0300Y         S1      
327FAN_2_PWM_IL     U65   -1          A01X+010724Y+045744X0280Y0360R270 S1      
327m0165            R5412 -2          A01X+014808Y+079650X0180Y0200R180 S1      
327m0165            VIA   -    M      A01X+015700Y+080150X0300Y         S1      
317m0165            J2    -12   D0380PA00X+016929Y+079138X0540Y    R090 S3      
327m0165            D269  -C   M      A01X+014817Y+080150X0220Y0240R180 S1      
327FAN_2_CS         PR38  -1          A06X+018700Y+029280X0198Y0197R090 S2      
317FAN_2_CS         VIA   -    M      A01X+018350Y+029950X0300Y         S1      
017FAN_2_CS         VIA   -    M      A06X+018350Y+029950X0200Y         S1      
017FAN_2_CS               -    MD0100PA00X+018350Y+029950                       
327FAN_2_CS         PU5   -19         A06X+017408Y+030494X0276Y0354R180 S2      
327m0166            R512  -2   M      A01X+016392Y+070600X0198Y0197R180 S1      
327m0166            R5490 -1          A01X+017592Y+070600X0198Y0197     S1      
317m0166            VIA   -    M      A01X+017144Y+070877X0200Y         S2      
017m0166            VIA   -    M      A06X+017144Y+070877X0260Y         S2      
017m0166                  -    MD0100PA00X+017144Y+070877                       
327m0166            U390  -8          A01X+015400Y+070732X0140Y0590R270 S1      
327m0167            VIA   -    M      A01X+012361Y+066421X0300Y         S1      
327m0167            R5468 -2          A01X+011558Y+066350X0198Y0197     S1      
327m0167            U8    -22         A01X+013150Y+066654X0140Y0590R090 S1      
327FAN_0_PWM        R5573 -1          A01X+015050Y+054200X0180Y0200R180 S1      
327FAN_0_PWM        R5597 -1   M      A01X+015050Y+054200X0180Y0200     S1      
317FAN_0_PWM        VIA   -    MD0100PA00X+015050Y+054450X0200Y         S0      
317FAN_0_PWM        VIA   -    M      A01X+011871Y+079750X0200Y         S2      
017FAN_0_PWM        VIA   -    M      A06X+011871Y+079750X0260Y         S2      
017FAN_0_PWM              -    MD0100PA00X+011871Y+079750                       
317FAN_0_PWM        VIA   -    MD0100PA00X+009400Y+081850X0200Y         S0      
327FAN_0_PWM        R336  -2   M      A01X+008850Y+117658X0198Y0197R090 S1      
317FAN_0_PWM        VIA   -    MD0100PA00X+008600Y+117658X0200Y    R090 S0      
327FAN_0_PWM        U60   -2          A01X+008850Y+118126X0160Y0200R180 S1      
327m0168            R4864 -2   M      A01X+002708Y+068600X0198Y0197     S1      
327m0168            R4867 -1          A01X+001808Y+068600X0198Y0197R180 S1      
327m0168            VIA   -    M      A01X+001985Y+069187X0300Y         S1      
327m0168            U26   -4          A01X+003526Y+068456X0160Y0200R090 S1      
327m0169            R5402 -2          A01X+014808Y+078650X0180Y0200R180 S1      
327m0169            VIA   -    M      A01X+015650Y+078770X0300Y         S1      
317m0169            J2    -14   D0380PA00X+016929Y+078350X0540Y    R090 S3      
327m0169            D270  -C          A01X+014867Y+079150X0220Y0240R180 S1      
317FAN_2_CLREF      VIA   -    M      A01X+016700Y+029631X0300Y         S1      
017FAN_2_CLREF      VIA   -    M      A06X+016700Y+029631X0200Y         S1      
017FAN_2_CLREF            -    MD0100PA00X+016700Y+029631                       
327FAN_2_CLREF      PC3120-2   M      A06X+016700Y+029280X0198Y0197R270 S2      
327FAN_2_CLREF      PU5   -24         A06X+016621Y+030494X0070Y0360R180 S2      
327FAN_2_CLREF      PR41  -1          A06X+017100Y+029280X0198Y0197R090 S2      
327m0170            R511  -2   M      A01X+012108Y+070400X0198Y0197     S1      
327m0170            R5489 -1          A01X+010958Y+070650X0198Y0197R180 S1      
327m0170            VIA   -    M      A01X+011234Y+070135X0300Y         S1      
327m0170            U390  -6          A01X+013100Y+070988X0140Y0590R270 S1      
327P12V_LED         VIA   -    M      A01X+016240Y+122990X0300Y         S1      
327P12V_LED         R5648 -1          A01X+017492Y+123650X0180Y0200R180 S1      
327P12V_LED         R5649 -1   M      A01X+017900Y+085442X0180Y0200R270 S1      
327P12V_LED         R5652 -1   M      A01X+017900Y+038742X0180Y0200R270 S1      
327P12V_LED         R5653 -1   M      A01X+012358Y+014450X0180Y0200     S1      
327P12V_LED         R5658 -1          A01X+008750Y+013608X0180Y0200R090 S1      
327P12V_LED         R5659 -1          A01X+001342Y+039300X0180Y0200R180 S1      
327P12V_LED         R5660 -1          A01X+007550Y+084958X0180Y0200R090 S1      
327P12V_LED         R5661 -1   M      A01X+003292Y+123550X0180Y0200R180 S1      
327P12V_LED         GF1   -S3         A06X+008799Y+001713X0320Y1970     S2      
327P12V_LED         Q12   -S          A01X+012210Y+013100X0400Y0500R270 S1      
317P12V_LED         VIA   -    MD0100PA00X+007600Y+013350X0200Y         S0      
327P12V_LED         Q13   -S   M      A01X+008040Y+014150X0400Y0500R090 S1      
327P12V_LED         Q11   -S          A01X+018610Y+038400X0400Y0500R270 S1      
317P12V_LED         VIA   -    MD0100PA00X+007550Y+085250X0200Y         S0      
327P12V_LED         Q15   -S          A01X+006440Y+085450X0400Y0500R090 S1      
327P12V_LED         Q10   -S          A01X+018560Y+085200X0400Y0500R270 S1      
317P12V_LED         VIA   -    M      A01X+010250Y+097950X0300Y         S1      
017P12V_LED         VIA   -    M      A06X+010250Y+097950X0200Y         S1      
017P12V_LED               -    MD0100PA00X+010250Y+097950                       
327P12V_LED         Q9    -S   M      A01X+016900Y+122990X0400Y0500R180 S1      
317P12V_LED         VIA   -    M      A01X+016550Y+122990X0200Y         S2      
017P12V_LED         VIA   -    M      A06X+016550Y+122990X0260Y         S2      
017P12V_LED               -    MD0100PA00X+016550Y+122990                       
327P12V_LED         Q16   -S          A01X+002750Y+122940X0400Y0500R180 S1      
327P12V_LED         VIA   -    M      A01X+012400Y+015063X0300Y         S1      
317P12V_LED         VIA   -    MD0100PA00X+008400Y+084495X0200Y         S0      
317P12V_LED         VIA   -    M      A01X+010700Y+038950X0200Y         S2      
017P12V_LED         VIA   -    M      A06X+010700Y+038950X0260Y         S2      
017P12V_LED               -    MD0100PA00X+010700Y+038950                       
327P12V_LED         Q14   -S   M      A01X+001460Y+037950X0400Y0500R270 S1      
317P12V_LED         VIA   -    MD0100PA00X+000750Y+004400X0200Y         S0      
327FAN_0_PWM_IL     U61   -1          A01X+010524Y+118244X0280Y0360R270 S1      
327FAN_0_PWM_IL     R5186 -2          A01X+014542Y+117850X0198Y0197R180 S1      
327FAN_0_PWM_IL     VIA   -    M      A01X+012300Y+117350X0300Y         S1      
327m0171            R4860 -2   M      A01X+002708Y+068050X0198Y0197     S1      
327m0171            R4863 -1          A01X+001808Y+068050X0198Y0197R180 S1      
317m0171            VIA   -    M      A01X+003273Y+067900X0200Y         S2      
017m0171            VIA   -    M      A06X+003273Y+067900X0260Y         S2      
017m0171                  -    MD0100PA00X+003273Y+067900                       
327m0171            U26   -6          A01X+003526Y+067944X0160Y0200R090 S1      
327FAN_5_FAIL_LED   VIA   -    M      A01X+012192Y+068438X0300Y         S1      
327FAN_5_FAIL_LED   R5105 -1          A01X+011558Y+068750X0198Y0197R180 S1      
327FAN_5_FAIL_LED   U8    -16         A01X+013150Y+068190X0140Y0590R090 S1      
327FAN_2_TEMP       PC2120-1          A06X+014850Y+029277X0198Y0197R090 S2      
327FAN_2_TEMP       PR40  -1   M      A06X+015242Y+029277X0198Y0197R090 S2      
317FAN_2_TEMP       VIA   -    M      A01X+015242Y+029650X0300Y         S1      
017FAN_2_TEMP       VIA   -    M      A06X+015242Y+029650X0200Y         S1      
017FAN_2_TEMP             -    MD0100PA00X+015242Y+029650                       
327FAN_2_TEMP       PU5   -29         A06X+015833Y+030494X0070Y0360R180 S2      
327m0172            R510  -2   M      A01X+012108Y+071100X0198Y0197     S1      
327m0172            R5488 -1          A01X+010958Y+071100X0198Y0197R180 S1      
317m0172            VIA   -    M      A01X+012508Y+071500X0200Y         S2      
017m0172            VIA   -    M      A06X+012508Y+071500X0260Y         S2      
017m0172                  -    MD0100PA00X+012508Y+071500                       
327m0172            U390  -4          A01X+013100Y+071500X0140Y0590R270 S1      
327FAN_3_PWM_IL     R5240 -2          A01X+014542Y+010784X0198Y0197R180 S1      
327FAN_3_PWM_IL     VIA   -    M      A01X+013570Y+010230X0300Y         S1      
327FAN_3_PWM_IL     U67   -1          A01X+010474Y+009844X0280Y0360R270 S1      
317m0173            VIA   -    M      A01X+002502Y+066985X0200Y         S2      
017m0173            VIA   -    M      A06X+002502Y+066985X0260Y         S2      
017m0173                  -    MD0100PA00X+002502Y+066985                       
327m0173            R4856 -2   M      A01X+002708Y+067250X0198Y0197     S1      
327m0173            R4859 -1          A01X+001808Y+067250X0198Y0197R180 S1      
327m0173            U25   -4          A01X+003526Y+067206X0160Y0200R090 S1      
317m0174            VIA   -    M      A01X+011100Y+050600X0200Y         S2      
017m0174            VIA   -    M      A06X+011100Y+050600X0260Y         S2      
017m0174                  -    MD0100PA00X+011100Y+050600                       
327m0174            U317  -26         A01X+011613Y+050692X0070Y0320R090 S1      
327m0174            R4944 -2          A01X+010208Y+050950X0198Y0197     S1      
327m0174            R4943 -1   M      A01X+010650Y+050358X0198Y0197R270 S1      
317FAN_4_FAIL_LED   VIA   -    M      A01X+012618Y+068892X0200Y         S2      
017FAN_4_FAIL_LED   VIA   -    M      A06X+012618Y+068892X0260Y         S2      
017FAN_4_FAIL_LED         -    MD0100PA00X+012618Y+068892                       
327FAN_4_FAIL_LED   R5103 -1          A01X+012242Y+069450X0198Y0197     S1      
327FAN_4_FAIL_LED   U8    -14         A01X+013150Y+068702X0140Y0590R090 S1      
327FAN_2_FAULT      PR36  -2          A01X+016700Y+029158X0180Y0200R270 S1      
317FAN_2_FAULT      VIA   -    M      A01X+017036Y+029886X0200Y         S2      
017FAN_2_FAULT      VIA   -    M      A06X+017036Y+029886X0260Y         S2      
017FAN_2_FAULT            -    MD0100PA00X+017036Y+029886                       
327FAN_2_FAULT      PU5   -22         A06X+016936Y+030494X0070Y0360R180 S2      
327m0175            R509  -2   M      A01X+012108Y+071800X0198Y0197     S1      
327m0175            R5487 -1          A01X+010958Y+071800X0198Y0197R180 S1      
327m0175            VIA   -    M      A01X+011998Y+072313X0300Y         S1      
327m0175            U390  -2          A01X+013100Y+072012X0140Y0590R270 S1      
327FAN_0_PWM_BUF    U60   -4          A01X+009106Y+118874X0160Y0200R180 S1      
327FAN_0_PWM_BUF    VIA   -    M      A01X+009776Y+119378X0300Y         S1      
327FAN_0_PWM_BUF    U61   -3          A01X+009776Y+118500X0280Y0360R270 S1      
327FAN_0_PWM_BUF    R5511 -2   M      A01X+009150Y+119342X0198Y0197R270 S1      
317m0176            VIA   -    M      A01X+002502Y+066385X0200Y         S2      
017m0176            VIA   -    M      A06X+002502Y+066385X0260Y         S2      
017m0176                  -    MD0100PA00X+002502Y+066385                       
327m0176            R4852 -2   M      A01X+002708Y+066650X0198Y0197     S1      
327m0176            R4855 -1          A01X+001808Y+066650X0198Y0197R180 S1      
327m0176            U25   -6          A01X+003526Y+066694X0160Y0200R090 S1      
327FAN_5_OK_LED     R5104 -1          A01X+011558Y+069300X0198Y0197R180 S1      
327FAN_5_OK_LED     VIA   -    M      A01X+012055Y+068965X0300Y         S1      
327FAN_5_OK_LED     U8    -15         A01X+013150Y+068446X0140Y0590R090 S1      
317FAN_2_P3V_R      VIA   -    M      A01X+016000Y+029850X0300Y         S1      
017FAN_2_P3V_R      VIA   -    M      A06X+016000Y+029850X0200Y         S1      
017FAN_2_P3V_R            -    MD0100PA00X+016000Y+029850                       
327FAN_2_P3V_R      PC31  -1          A06X+016050Y+029280X0198Y0197R090 S2      
327FAN_2_P3V_R      PU5   -27         A06X+016148Y+030494X0070Y0360R180 S2      
327FAN_2_P3V_R      PR37  -1   M      A01X+015450Y+028842X0198Y0197R090 S1      
327FAN_2_P3V_R      PR35  -2          A01X+015892Y+028800X0198Y0197R180 S1      
327m0177            R513  -1   M      A01X+013258Y+072850X0198Y0197R180 S1      
317m0177            VIA   -    M      A01X+013650Y+072850X0200Y         S2      
017m0177            VIA   -    M      A06X+013650Y+072850X0260Y         S2      
017m0177                  -    MD0100PA00X+013650Y+072850                       
327m0177            U390  -9          A01X+015400Y+070988X0140Y0590R270 S1      
327m0177            U390  -3          A01X+013100Y+071756X0140Y0590R270 S1      
327m0177            U390  -5          A01X+013100Y+071244X0140Y0590R270 S1      
327m0177            U390  -1   M      A01X+013100Y+072268X0140Y0590R270 S1      
327m0177            R4959 -1          A01X+012108Y+075200X0198Y0197R180 S1      
327m0177            U389  -1   M      A01X+013150Y+075368X0140Y0590R270 S1      
327m0177            U389  -3          A01X+013150Y+074856X0140Y0590R270 S1      
327m0177            U389  -5          A01X+013150Y+074344X0140Y0590R270 S1      
317m0177            VIA   -    MD0100PA00X+013650Y+074200X0200Y         S0      
327m0177            U389  -9          A01X+015450Y+074088X0140Y0590R270 S1      
327m0178            R5523 -2   M      A01X+006800Y+057658X0198Y0197R090 S1      
327m0178            R5524 -1          A01X+006800Y+056808X0198Y0197R270 S1      
327m0178            VIA   -    M      A01X+007290Y+058250X0300Y         S1      
327m0178            U321  -1          A01X+008342Y+058700X0140Y0590     S1      
327FAN_1_PWM_OL     R5196 -1          A01X+014592Y+083411X0198Y0197     S1      
327FAN_1_PWM_OL     VIA   -    M      A01X+012200Y+083850X0300Y         S1      
327FAN_1_PWM_OL     U63   -2          A01X+010524Y+082456X0280Y0360R270 S1      
327m0179            VIA   -    M      A01X+005416Y+068976X0300Y         S1      
327m0179            R5506 -2   M      A01X+005092Y+068500X0198Y0197R180 S1      
327m0179            R5502 -2          A01X+006892Y+068500X0198Y0197R180 S1      
327m0179            C1948 -1   M      A01X+005992Y+068500X0198Y0197     S1      
327m0179            U26   -3          A01X+004274Y+068456X0160Y0200R090 S1      
327FAN_2_FAIL_LED   R5099 -1          A01X+016992Y+068850X0198Y0197     S1      
327FAN_2_FAIL_LED   VIA   -    M      A01X+016503Y+068599X0300Y         S1      
327FAN_2_FAIL_LED   U8    -9          A01X+015450Y+068190X0140Y0590R090 S1      
327FAN_2_MODE       VIA   -    M      A06X+015027Y+029859X0260Y         S2      
327FAN_2_MODE       PU5   -30         A06X+015676Y+030494X0276Y0354R180 S2      
317FAN_2_MODE       VIA   -    MD0100PA00X+014950Y+029550X0200Y         S0      
327FAN_2_MODE       PR37  -2   M      A01X+015450Y+029158X0198Y0197R090 S1      
327FAN_2_MODE       PR39  -1          A01X+015892Y+029200X0198Y0197     S1      
327m0180            R4958 -2   M      A01X+016392Y+073300X0198Y0197R180 S1      
327m0180            R5494 -1          A01X+017592Y+073300X0198Y0197     S1      
317m0180            VIA   -    M      A01X+017159Y+073568X0200Y         S2      
017m0180            VIA   -    M      A06X+017159Y+073568X0260Y         S2      
017m0180                  -    MD0100PA00X+017159Y+073568                       
327m0180            U389  -8          A01X+015450Y+073832X0140Y0590R270 S1      
327m0181            R5473 -2   M      A01X+007500Y+057658X0198Y0197R090 S1      
327m0181            R5471 -1          A01X+007500Y+056808X0198Y0197R270 S1      
327m0181            VIA   -    M      A01X+007993Y+057900X0300Y         S1      
327m0181            U321  -2          A01X+008598Y+058700X0140Y0590     S1      
327FAN_0_PWM_OL     VIA   -    M      A01X+011228Y+119460X0300Y         S1      
327FAN_0_PWM_OL     R5184 -1          A01X+014592Y+119750X0198Y0197     S1      
327FAN_0_PWM_OL     U61   -2          A01X+010524Y+118756X0280Y0360R270 S1      
317m0182            VIA   -    M      A01X+005298Y+068165X0200Y         S2      
017m0182            VIA   -    M      A06X+005298Y+068165X0260Y         S2      
017m0182                  -    MD0100PA00X+005298Y+068165                       
327m0182            R5505 -2   M      A01X+005092Y+067900X0198Y0197R180 S1      
327m0182            R5501 -2          A01X+006892Y+067900X0198Y0197R180 S1      
327m0182            C1946 -1   M      A01X+005992Y+067900X0198Y0197     S1      
327m0182            U26   -1          A01X+004274Y+067944X0160Y0200R090 S1      
327FAN_6_FAIL_LED   VIA   -    M      A01X+012030Y+067706X0300Y         S1      
327FAN_6_FAIL_LED   R5108 -1          A01X+011558Y+067950X0198Y0197R180 S1      
327FAN_6_FAIL_LED   U8    -18         A01X+013150Y+067678X0140Y0590R090 S1      
327m0183            R4957 -2   M      A01X+012108Y+073100X0198Y0197     S1      
327m0183            R5493 -1          A01X+010958Y+073100X0198Y0197R180 S1      
317m0183            VIA   -    M      A01X+011900Y+073400X0200Y         S2      
017m0183            VIA   -    M      A06X+011900Y+073400X0260Y         S2      
017m0183                  -    MD0100PA00X+011900Y+073400                       
327m0183            U389  -6          A01X+013150Y+074088X0140Y0590R270 S1      
327m0184            R5472 -2          A01X+008080Y+063992X0198Y0197R270 S1      
327m0184            R5470 -1   M      A01X+008090Y+063158X0198Y0197R270 S1      
327m0184            VIA   -    M      A01X+008040Y+062120X0300Y         S1      
327m0184            U321  -21         A01X+009110Y+061000X0140Y0590     S1      
327FAN_1_PWM        R5577 -1          A01X+015058Y+052200X0180Y0200R180 S1      
327FAN_1_PWM        R5601 -1   M      A01X+015058Y+052200X0180Y0200     S1      
327FAN_1_PWM        VIA   -    M      A01X+009592Y+081358X0300Y         S1      
317FAN_1_PWM        VIA   -    MD0100PA00X+015058Y+052450X0200Y         S0      
327FAN_1_PWM        R344  -2   M      A01X+008850Y+081358X0198Y0197R090 S1      
317FAN_1_PWM        VIA   -    MD0100PA00X+012184Y+077597X0200Y         S0      
327FAN_1_PWM        U62   -2          A01X+008850Y+081826X0160Y0200R180 S1      
317m0185            VIA   -    M      A01X+004695Y+067250X0200Y         S2      
017m0185            VIA   -    M      A06X+004695Y+067250X0260Y         S2      
017m0185                  -    MD0100PA00X+004695Y+067250                       
327m0185            R5504 -2   M      A01X+005092Y+067250X0198Y0197R180 S1      
327m0185            R5500 -2          A01X+006892Y+067250X0198Y0197R180 S1      
327m0185            C1942 -1   M      A01X+005992Y+067250X0198Y0197     S1      
327m0185            U25   -3          A01X+004274Y+067206X0160Y0200R090 S1      
327FAN_2_OK_LED     R5098 -1          A01X+016992Y+068450X0198Y0197     S1      
317FAN_2_OK_LED     VIA   -    M      A01X+016764Y+068222X0200Y         S2      
017FAN_2_OK_LED     VIA   -    M      A06X+016764Y+068222X0260Y         S2      
017FAN_2_OK_LED           -    MD0100PA00X+016764Y+068222                       
327FAN_2_OK_LED     U8    -8          A01X+015450Y+067934X0140Y0590R090 S1      
327FAN_2_P5V        PC32  -1          A06X+015642Y+029277X0198Y0197R090 S2      
327FAN_2_P5V        VIA   -    M      A06X+015710Y+029780X0260Y         S2      
327FAN_2_P5V        PU5   -28         A06X+015991Y+030494X0070Y0360R180 S2      
327m0186            R4956 -2          A01X+012108Y+073800X0198Y0197     S1      
327m0186            R5492 -1          A01X+010958Y+073800X0198Y0197R180 S1      
317m0186            VIA   -    M      A01X+011486Y+074150X0200Y         S2      
017m0186            VIA   -    M      A06X+011486Y+074150X0260Y         S2      
017m0186                  -    MD0100PA00X+011486Y+074150                       
327m0186            U389  -4          A01X+013150Y+074600X0140Y0590R270 S1      
327FAN_2_PWM_OL     R5216 -1          A01X+014592Y+047073X0198Y0197     S1      
327FAN_2_PWM_OL     VIA   -    M      A01X+012250Y+047350X0300Y         S1      
327FAN_2_PWM_OL     U65   -2          A01X+010724Y+046256X0280Y0360R270 S1      
317m0187            VIA   -    M      A01X+004695Y+066650X0200Y         S2      
017m0187            VIA   -    M      A06X+004695Y+066650X0260Y         S2      
017m0187                  -    MD0100PA00X+004695Y+066650                       
327m0187            R5503 -2   M      A01X+005092Y+066650X0198Y0197R180 S1      
327m0187            R5499 -2          A01X+006892Y+066650X0198Y0197R180 S1      
327m0187            C1940 -1   M      A01X+005992Y+066650X0198Y0197     S1      
327m0187            U25   -1          A01X+004274Y+066694X0160Y0200R090 S1      
327FAN_4_OK_LED     R5102 -1          A01X+013042Y+069450X0198Y0197     S1      
327FAN_4_OK_LED     VIA   -    M      A01X+013935Y+069491X0300Y         S1      
327FAN_4_OK_LED     U8    -13         A01X+013150Y+068958X0140Y0590R090 S1      
327FAN_2_IMON       PR42  -2          A06X+018300Y+029280X0198Y0197R270 S2      
327FAN_2_IMON       VIA   -    M      A06X+017900Y+029850X0260Y         S2      
327FAN_2_IMON       PU5   -20         A06X+017251Y+030494X0070Y0360R180 S2      
327m0188            R4955 -2   M      A01X+012108Y+074500X0198Y0197     S1      
327m0188            R5491 -1          A01X+010958Y+074500X0198Y0197R180 S1      
317m0188            VIA   -    M      A01X+012535Y+074928X0200Y         S2      
017m0188            VIA   -    M      A06X+012535Y+074928X0260Y         S2      
017m0188                  -    MD0100PA00X+012535Y+074928                       
327m0188            U389  -2          A01X+013150Y+075112X0140Y0590R270 S1      
327FAN_7_OK_LED     VIA   -    M      A01X+012482Y+067422X0300Y         S1      
327FAN_7_OK_LED     R5110 -1          A01X+011558Y+067550X0198Y0197R180 S1      
327FAN_7_OK_LED     U8    -19         A01X+013150Y+067422X0140Y0590R090 S1      
327FAN_2_FAULT_R    PR36  -1          A01X+016700Y+028842X0180Y0200R270 S1      
327FAN_2_FAULT_R    VIA   -    M      A01X+016113Y+028300X0300Y         S1      
327FAN_2_FAULT_R    PR35  -1          A01X+016208Y+028800X0198Y0197R180 S1      
327m0189            C2086 -1   M      A01X+018442Y+073300X0198Y0197     S1      
317m0189            VIA   -    MD0100PA00X+011950Y+099200X0200Y         S0      
327m0189            R5494 -2          A01X+017908Y+073300X0198Y0197     S1      
317m0189            VIA   -    M      A01X+018442Y+073800X0300Y         S1      
017m0189            VIA   -    M      A06X+018442Y+073800X0200Y         S1      
017m0189                  -    MD0100PA00X+018442Y+073800                       
327m0189            U385  -2          A06X+005235Y+100750X0130Y0460R090 S2      
317m0189            VIA   -    MD0100PA00X+005615Y+100750X0200Y         S0      
317P52V_FAN_EN_R    VIA   -    M      A01X+008750Y+008330X0200Y         S2      
017P52V_FAN_EN_R    VIA   -    M      A06X+008750Y+008330X0260Y         S2      
017P52V_FAN_EN_R          -    MD0100PA00X+008750Y+008330                       
327P52V_FAN_EN_R    R4970 -1          A01X+009792Y+008155X0198Y0197     S1      
327P52V_FAN_EN_R    GF1   -S2         A06X+009299Y+001713X0320Y1970     S2      
327FAN_3_PWM_BUF    U67   -3          A01X+009726Y+010100X0280Y0360R270 S1      
317FAN_3_PWM_BUF    VIA   -    M      A01X+009443Y+010383X0200Y         S2      
017FAN_3_PWM_BUF    VIA   -    M      A06X+009443Y+010383X0260Y         S2      
017FAN_3_PWM_BUF          -    MD0100PA00X+009443Y+010383                       
327FAN_3_PWM_BUF    R5514 -2          A01X+009150Y+010942X0198Y0197R270 S1      
327FAN_3_PWM_BUF    U66   -4   M      A01X+009106Y+010474X0160Y0200R180 S1      
327FAN_0_OK_LED     R5094 -1          A01X+016992Y+066850X0198Y0197     S1      
327FAN_0_OK_LED     VIA   -    M      A01X+016457Y+066910X0300Y         S1      
327FAN_0_OK_LED     U8    -4          A01X+015450Y+066910X0140Y0590R090 S1      
327FAN_2_TIMER      PC34  -1          A06X+017500Y+029280X0198Y0197R090 S2      
327FAN_2_TIMER      PU5   -23         A06X+016778Y+030494X0070Y0360R180 S2      
327FAN_3_PWM        U66   -2          A01X+008850Y+009726X0160Y0200R180 S1      
327FAN_3_PWM        R360  -2   M      A01X+008842Y+009200X0198Y0197R180 S1      
317FAN_3_PWM        VIA   -    M      A01X+008600Y+009200X0200Y         S2      
017FAN_3_PWM        VIA   -    M      A06X+008600Y+009200X0260Y         S2      
017FAN_3_PWM              -    MD0100PA00X+008600Y+009200                       
327FAN_3_PWM        R5583 -1          A01X+015058Y+049200X0180Y0200R180 S1      
327FAN_3_PWM        R5607 -1   M      A01X+015058Y+049200X0180Y0200     S1      
317FAN_3_PWM        VIA   -    MD0100PA00X+015058Y+049450X0200Y         S0      
327FAN_1_OK_LED     R5096 -1          A01X+016992Y+067650X0198Y0197     S1      
317FAN_1_OK_LED     VIA   -    M      A01X+016768Y+067425X0200Y         S2      
017FAN_1_OK_LED     VIA   -    M      A06X+016768Y+067425X0260Y         S2      
017FAN_1_OK_LED           -    MD0100PA00X+016768Y+067425                       
327FAN_1_OK_LED     U8    -6          A01X+015450Y+067422X0140Y0590R090 S1      
327FAN_2_SS         PC33  -1          A06X+017900Y+029280X0198Y0197R090 S2      
317FAN_2_SS         VIA   -    M      A01X+017386Y+029850X0300Y         S1      
017FAN_2_SS         VIA   -    M      A06X+017386Y+029850X0200Y         S1      
017FAN_2_SS               -    MD0100PA00X+017386Y+029850                       
327FAN_2_SS         PU5   -21         A06X+017093Y+030494X0070Y0360R180 S2      
327m0190            C2085 -1   M      A01X+009858Y+073100X0198Y0197R180 S1      
327m0190            VIA   -    M      A01X+001982Y+075460X0300Y         S1      
327m0190            U383  -2          A06X+002750Y+099250X0130Y0460R270 S2      
317m0190            VIA   -    MD0100PA00X+002370Y+099226X0200Y    R180 S0      
327m0190            R5493 -2          A01X+010642Y+073100X0198Y0197R180 S1      
317m0190            VIA   -    MD0100PA00X+001282Y+075150X0200Y         S0      
327FAN_2_PWM_BUF    R5513 -2          A01X+009150Y+046742X0198Y0197R270 S1      
317FAN_2_PWM_BUF    VIA   -    M      A01X+009500Y+046274X0200Y         S2      
017FAN_2_PWM_BUF    VIA   -    M      A06X+009500Y+046274X0260Y         S2      
017FAN_2_PWM_BUF          -    MD0100PA00X+009500Y+046274                       
327FAN_2_PWM_BUF    U65   -3          A01X+009976Y+046000X0280Y0360R270 S1      
327FAN_2_PWM_BUF    U64   -4   M      A01X+009106Y+046274X0160Y0200R180 S1      
327FAN_3_FAIL_LED   R5101 -1          A01X+016992Y+069650X0198Y0197     S1      
327FAN_3_FAIL_LED   VIA   -    M      A01X+016131Y+069688X0300Y         S1      
327FAN_3_FAIL_LED   U8    -11         A01X+015450Y+068702X0140Y0590R090 S1      
327FAN_3_OK_LED     R5100 -1          A01X+016992Y+069250X0198Y0197     S1      
317FAN_3_OK_LED     VIA   -    M      A01X+016706Y+069250X0200Y         S2      
017FAN_3_OK_LED     VIA   -    M      A06X+016706Y+069250X0260Y         S2      
017FAN_3_OK_LED           -    MD0100PA00X+016706Y+069250                       
327FAN_3_OK_LED     U8    -10         A01X+015450Y+068446X0140Y0590R090 S1      
317m0191            VIA   -    MD0100PA00X+005565Y+028073X0200Y         S0      
327m0191            U361  -2          A06X+005185Y+028073X0130Y0460R090 S2      
317m0191            VIA   -    M      A01X+001180Y+028400X0300Y         S1      
017m0191            VIA   -    M      A06X+001180Y+028400X0200Y         S1      
017m0191                  -    MD0100PA00X+001180Y+028400                       
327m0191            R5492 -2          A01X+010642Y+073800X0198Y0197R180 S1      
327m0191            C2084 -1   M      A01X+009858Y+073800X0198Y0197R180 S1      
317m0191            VIA   -    MD0100PA00X+003700Y+075690X0200Y         S0      
327FAN_7_FAIL_LED   VIA   -    M      A01X+012040Y+067082X0300Y         S1      
327FAN_7_FAIL_LED   R5111 -1          A01X+011558Y+067150X0198Y0197R180 S1      
327FAN_7_FAIL_LED   U8    -20         A01X+013150Y+067166X0140Y0590R090 S1      
327FAN_1_PWM_IL     U63   -1          A01X+010524Y+081944X0280Y0360R270 S1      
327FAN_1_PWM_IL     R5200 -2          A01X+014542Y+081511X0198Y0197R180 S1      
327FAN_1_PWM_IL     VIA   -    M      A01X+012150Y+080900X0300Y         S1      
327FAN_0_FAIL_LED   R5095 -1          A01X+016992Y+067250X0198Y0197     S1      
317FAN_0_FAIL_LED   VIA   -    M      A01X+015905Y+067166X0200Y         S2      
017FAN_0_FAIL_LED   VIA   -    M      A06X+015905Y+067166X0260Y         S2      
017FAN_0_FAIL_LED         -    MD0100PA00X+015905Y+067166                       
327FAN_0_FAIL_LED   U8    -5          A01X+015450Y+067166X0140Y0590R090 S1      
327m0192            U359  -2          A06X+002750Y+026573X0130Y0460R270 S2      
317m0192            VIA   -    M      A01X+002400Y+027600X0300Y    R180 S1      
017m0192            VIA   -    M      A06X+002400Y+027600X0200Y    R180 S1      
017m0192                  -    MD0100PA00X+002400Y+027600                       
327m0192            R5491 -2          A01X+010642Y+074500X0198Y0197R180 S1      
327m0192            C2083 -1   M      A01X+009858Y+074500X0198Y0197R180 S1      
317m0192            VIA   -    MD0100PA00X+003400Y+075700X0200Y         S0      
327FAN_1_PWM_BUF    R5512 -2          A01X+009150Y+083042X0198Y0197R270 S1      
317FAN_1_PWM_BUF    VIA   -    M      A01X+009400Y+082574X0200Y         S2      
017FAN_1_PWM_BUF    VIA   -    M      A06X+009400Y+082574X0260Y         S2      
017FAN_1_PWM_BUF          -    MD0100PA00X+009400Y+082574                       
327FAN_1_PWM_BUF    U63   -3          A01X+009776Y+082200X0280Y0360R270 S1      
327FAN_1_PWM_BUF    U62   -4   M      A01X+009106Y+082574X0160Y0200R180 S1      
327FAN_6_OK_LED     VIA   -    M      A01X+012483Y+067987X0300Y         S1      
327FAN_6_OK_LED     R5107 -1          A01X+011558Y+068350X0198Y0197R180 S1      
327FAN_6_OK_LED     U8    -17         A01X+013150Y+067934X0140Y0590R090 S1      
327FAN_1_FAIL_LED   R5097 -1          A01X+016992Y+068050X0198Y0197     S1      
327FAN_1_FAIL_LED   VIA   -    M      A01X+016510Y+067823X0300Y         S1      
327FAN_1_FAIL_LED   U8    -7          A01X+015450Y+067678X0140Y0590R090 S1      
327m0193            R5490 -2          A01X+017908Y+070600X0198Y0197     S1      
327m0193            C2082 -1   M      A01X+018792Y+070600X0198Y0197     S1      
317m0193            VIA   -    M      A01X+018792Y+070100X0300Y         S1      
017m0193            VIA   -    M      A06X+018792Y+070100X0200Y         S1      
017m0193                  -    MD0100PA00X+018792Y+070100                       
317m0193            VIA   -    MD0100PA00X+014739Y+026573X0200Y    R180 S0      
327m0193            U74   -2          A06X+015119Y+026573X0130Y0460R270 S2      
327m0194            C2081 -1          A01X+010208Y+070650X0198Y0197R180 S1      
317m0194            VIA   -    MD0100PA00X+016495Y+028073X0200Y         S0      
327m0194            U381  -2          A06X+016115Y+028073X0130Y0460R090 S2      
327m0194            R5489 -2   M      A01X+010642Y+070650X0198Y0197R180 S1      
317m0194            VIA   -    M      A01X+019400Y+055000X0300Y         S1      
017m0194            VIA   -    M      A06X+019400Y+055000X0200Y         S1      
017m0194                  -    MD0100PA00X+019400Y+055000                       
327m0195            C2080 -1   M      A01X+010208Y+071100X0198Y0197R180 S1      
327m0195            VIA   -    M      A01X+010112Y+071588X0300Y         S1      
327m0195            R5488 -2          A01X+010642Y+071100X0198Y0197R180 S1      
317m0195            VIA   -    MD0100PA00X+018704Y+073000X0200Y         S0      
317m0195            VIA   -    MD0100PA00X+014739Y+099565X0200Y    R180 S0      
327m0195            U379  -2          A06X+015119Y+099565X0130Y0460R270 S2      
327SMB_FAN7_SDA     R5245 -2          A01X+005808Y+116400X0198Y0197     S1      
317SMB_FAN7_SDA     VIA   -    MD0100PA00X+006150Y+116000X0200Y         S0      
327SMB_FAN7_SDA     R4884 -2          A01X+009100Y+063158X0198Y0197R090 S1      
317SMB_FAN7_SDA     VIA   -    M      A01X+008830Y+063980X0200Y         S2      
017SMB_FAN7_SDA     VIA   -    M      A06X+008830Y+063980X0260Y         S2      
017SMB_FAN7_SDA           -    MD0100PA00X+008830Y+063980                       
327m0196            U377  -2          A06X+016115Y+100750X0130Y0460R090 S2      
317m0196            VIA   -    MD0100PA00X+016495Y+100750X0200Y         S0      
327m0196            R5487 -2          A01X+010642Y+071800X0198Y0197R180 S1      
317m0196            VIA   -    M      A01X+019030Y+072520X0200Y         S2      
017m0196            VIA   -    M      A06X+019030Y+072520X0260Y         S2      
017m0196                  -    MD0100PA00X+019030Y+072520                       
327SMB_FAN7_SCL     R5243 -1          A01X+005808Y+115200X0198Y0197R180 S1      
317SMB_FAN7_SCL     VIA   -    MD0100PA00X+006048Y+115200X0200Y         S0      
327SMB_FAN7_SCL     R4883 -2          A01X+008700Y+063158X0198Y0197R090 S1      
317SMB_FAN7_SCL     VIA   -    M      A01X+008750Y+063470X0200Y    R090 S2      
017SMB_FAN7_SCL     VIA   -    M      A06X+008750Y+063470X0260Y    R090 S2      
017SMB_FAN7_SCL           -    MD0100PA00X+008750Y+063470                       
327FAN_7_P5V        PC57  -1          A06X+004612Y+101954X0198Y0197R090 S2      
327FAN_7_P5V        VIA   -    M      A06X+004866Y+102565X0260Y         S2      
327FAN_7_P5V        PU9   -28         A06X+005111Y+103171X0070Y0360R180 S2      
327FAN_7_TIMER      PC59  -1          A06X+006450Y+101958X0198Y0197R090 S2      
327FAN_7_TIMER      PU9   -23         A06X+005898Y+103171X0070Y0360R180 S2      
327m0197            R105  -2   M      A01X+001492Y+066000X0198Y0197R180 S1      
317m0197            VIA   -    M      A01X+019199Y+053634X0200Y         S2      
017m0197            VIA   -    M      A06X+019199Y+053634X0260Y         S2      
017m0197                  -    MD0100PA00X+019199Y+053634                       
327m0197            U7    -7          A01X+002900Y+070722X0140Y0590R270 S1      
327m0197            U391  -2          A06X+013648Y+026977X0160Y0240     S2      
317m0197            VIA   -    MD0100PA00X+013648Y+027247X0200Y    R180 S0      
327FAN_7_IMON       PR78  -2          A06X+007256Y+101958X0198Y0197R270 S2      
327FAN_7_IMON       VIA   -    M      A06X+007121Y+102429X0260Y         S2      
327FAN_7_IMON       PU9   -20         A06X+006371Y+103171X0070Y0360R180 S2      
317m0198            VIA   -    M      A01X+002033Y+071117X0200Y         S2      
017m0198            VIA   -    M      A06X+002033Y+071117X0260Y         S2      
017m0198                  -    MD0100PA00X+002033Y+071117                       
327m0198            U7    -5          A01X+002900Y+071234X0140Y0590R270 S1      
327m0198            R103  -2          A01X+001492Y+064550X0198Y0197R180 S1      
317m0198            VIA   -    MD0100PA00X+001251Y+064701X0200Y    R180 S0      
317m0198            VIA   -    MD0100PA00X+001483Y+076361X0200Y         S0      
317m0198            VIA   -    MD0100PA00X+014900Y+085450X0200Y         S0      
327m0198            U395  -2          A06X+013648Y+099969X0160Y0240     S2      
317m0198            VIA   -    MD0100PA00X+013648Y+100239X0200Y         S0      
327SMB_FAN6_SDA     R4880 -2          A01X+010500Y+063158X0198Y0197R090 S1      
317SMB_FAN6_SDA     VIA   -    MD0100PA00X+010600Y+063450X0200Y    R090 S0      
327SMB_FAN6_SDA     R5225 -2          A01X+005808Y+079261X0198Y0197     S1      
317SMB_FAN6_SDA     VIA   -    M      A01X+009950Y+078700X0200Y         S2      
017SMB_FAN6_SDA     VIA   -    M      A06X+009950Y+078700X0260Y         S2      
017SMB_FAN6_SDA           -    MD0100PA00X+009950Y+078700                       
327FAN_7_P3V_R      PC56  -1          A06X+005000Y+101958X0198Y0197R090 S2      
317FAN_7_P3V_R      VIA   -    M      A01X+005000Y+102300X0300Y         S1      
017FAN_7_P3V_R      VIA   -    M      A06X+005000Y+102300X0200Y         S1      
017FAN_7_P3V_R            -    MD0100PA00X+005000Y+102300                       
327FAN_7_P3V_R      PU9   -27         A06X+005269Y+103171X0070Y0360R180 S2      
327FAN_7_P3V_R      PR71  -2   M      A01X+005642Y+101600X0198Y0197R180 S1      
327FAN_7_P3V_R      PR73  -1          A01X+005642Y+102000X0198Y0197     S1      
327m0199            U7    -4          A01X+002900Y+071490X0140Y0590R270 S1      
317m0199            VIA   -    MD0100PA00X+001571Y+071001X0200Y         S0      
327m0199            R100  -2          A01X+001492Y+064100X0198Y0197R180 S1      
317m0199            VIA   -    M      A01X+001200Y+064100X0200Y    R180 S2      
017m0199            VIA   -    M      A06X+001200Y+064100X0260Y    R180 S2      
017m0199                  -    MD0100PA00X+001200Y+064100                       
317m0199            VIA   -    MD0100PA00X+001242Y+076526X0200Y         S0      
327m0199            U394  -2          A06X+017586Y+100346X0160Y0240R180 S2      
317m0199            VIA   -    MD0100PA00X+017586Y+100076X0200Y         S0      
317m0199            VIA   -    MD0100PA00X+014600Y+085450X0200Y         S0      
327FAN_7_FAULT      PR72  -2          A01X+006350Y+101958X0180Y0200R270 S1      
317FAN_7_FAULT      VIA   -    M      A01X+006250Y+102550X0200Y         S2      
017FAN_7_FAULT      VIA   -    M      A06X+006250Y+102550X0260Y         S2      
017FAN_7_FAULT            -    MD0100PA00X+006250Y+102550                       
327FAN_7_FAULT      PU9   -22         A06X+006056Y+103171X0070Y0360R180 S2      
327m0200            U7    -6          A01X+002900Y+070978X0140Y0590R270 S1      
317m0200            VIA   -    MD0100PA00X+002045Y+070805X0200Y         S0      
327m0200            R104  -2          A01X+001492Y+065400X0198Y0197R180 S1      
317m0200            VIA   -    MD0100PA00X+018925Y+054175X0200Y         S0      
317m0200            VIA   -    M      A01X+001239Y+065351X0200Y    R180 S2      
017m0200            VIA   -    M      A06X+001239Y+065351X0260Y    R180 S2      
017m0200                  -    MD0100PA00X+001239Y+065351                       
327m0200            U396  -2          A06X+017586Y+027668X0160Y0240R180 S2      
317m0200            VIA   -    MD0100PA00X+017586Y+027398X0200Y         S0      
327P3V3_AUX         R5395 -1          A01X+012700Y+007142X0198Y0197R090 S1      
327P3V3_AUX         GF1   -S4         A06X+008299Y+001713X0320Y1970     S2      
327P3V3_AUX         R4988 -1          A01X+010650Y+005628X0198Y0197R270 S1      
327P3V3_AUX         R360  -1          A01X+009158Y+009200X0198Y0197R180 S1      
327P3V3_AUX         R4989 -1   M      A01X+009150Y+005628X0198Y0197R270 S1      
317P3V3_AUX         VIA   -    MD0100PA00X+008880Y+010020X0200Y         S0      
317P3V3_AUX         VIA   -    MD0100PA00X+008298Y+005333X0200Y         S0      
317P3V3_AUX         VIA   -    MD0100PA00X+008100Y+119342X0200Y         S0      
327P3V3_AUX         C100  -1   M      A01X+008550Y+119342X0198Y0197R090 S1      
327P3V3_AUX         U60   -5          A01X+008594Y+118874X0160Y0200R180 S1      
327P3V3_AUX         R5511 -1          A01X+009150Y+119658X0198Y0197R270 S1      
317P3V3_AUX         VIA   -    MD0100PA00X+018900Y+075850X0200Y         S0      
327P3V3_AUX         C2071 -1          A01X+001279Y+099092X0198Y0197R090 S1      
317P3V3_AUX         VIA   -    MD0100PA00X+003888Y+098994X0200Y    R180 S0      
327P3V3_AUX         U383  -5          A06X+003508Y+098994X0130Y0460R270 S2      
327P3V3_AUX         C2070 -1          A01X+003587Y+099050X0198Y0197R180 S1      
317P3V3_AUX         VIA   -    MD0100PA00X+007300Y+101050X0200Y         S0      
327P3V3_AUX         U398  -5          A06X+007001Y+101054X0240Y0240R270 S2      
327P3V3_AUX         C2072 -1          A01X+006706Y+100908X0198Y0197R270 S1      
317P3V3_AUX         VIA   -    MD0100PA00X+004097Y+101006X0200Y         S0      
327P3V3_AUX         U385  -5          A06X+004477Y+101006X0130Y0460R090 S2      
327P3V3_AUX         C2073 -1          A01X+004399Y+100950X0198Y0197     S1      
327P3V3_AUX         R5387 -1          A01X+012700Y+115942X0198Y0197R090 S1      
317P3V3_AUX         VIA   -    MD0100PA00X+012700Y+115702X0200Y         S0      
327P3V3_AUX         R5522 -1          A01X+011550Y+115158X0198Y0197R270 S1      
317P3V3_AUX         VIA   -    MD0100PA00X+011800Y+115158X0200Y    R270 S0      
327P3V3_AUX         R5379 -1          A01X+007650Y+116058X0198Y0197R270 S1      
317P3V3_AUX         VIA   -    MD0100PA00X+007650Y+116298X0200Y    R180 S0      
327P3V3_AUX         R5378 -1          A01X+007650Y+117658X0198Y0197R270 S1      
317P3V3_AUX         VIA   -    MD0100PA00X+007911Y+117658X0200Y    R180 S0      
327P3V3_AUX         R336  -1          A01X+008850Y+117342X0198Y0197R090 S1      
317P3V3_AUX         VIA   -    MD0100PA00X+009100Y+117342X0200Y    R090 S0      
327P3V3_AUX         R5384 -1          A01X+012700Y+114542X0198Y0197R090 S1      
317P3V3_AUX         VIA   -    MD0100PA00X+012700Y+114300X0200Y         S0      
327P3V3_AUX         C2093 -1   M      A01X+011850Y+113158X0198Y0197R270 S1      
317P3V3_AUX         VIA   -    MD0100PA00X+012100Y+113158X0200Y    R270 S0      
327P3V3_AUX         U402  -5          A01X+011806Y+113626X0160Y0200     S1      
327P3V3_AUX         R5518 -1          A01X+011250Y+112842X0198Y0197R090 S1      
317P3V3_AUX         VIA   -    MD0100PA00X+011000Y+112842X0200Y    R270 S0      
327P3V3_AUX         C2064 -1          A01X+015278Y+100950X0198Y0197     S1      
327P3V3_AUX         U377  -5          A06X+015357Y+101006X0130Y0460R090 S2      
317P3V3_AUX         VIA   -    MD0100PA00X+014977Y+101006X0200Y         S0      
327P3V3_AUX         C2065 -1          A01X+017586Y+100908X0198Y0197R270 S1      
327P3V3_AUX         U394  -5          A06X+017881Y+101054X0240Y0240R270 S2      
317P3V3_AUX         VIA   -    MD0100PA00X+017881Y+100784X0200Y         S0      
327P3V3_AUX         C2067 -1          A01X+013648Y+099407X0198Y0197R090 S1      
327P3V3_AUX         U395  -5          A06X+013353Y+099261X0240Y0240R090 S2      
317P3V3_AUX         VIA   -    MD0100PA00X+013353Y+099531X0200Y    R180 S0      
327P3V3_AUX         U397  -5          A06X+001205Y+099146X0240Y0240R090 S2      
317P3V3_AUX         VIA   -    MD0100PA00X+000984Y+099473X0200Y         S0      
327P3V3_AUX         C2066 -1          A01X+015956Y+099365X0198Y0197R180 S1      
327P3V3_AUX         U379  -5          A06X+015877Y+099309X0130Y0460R270 S2      
317P3V3_AUX         VIA   -    MD0100PA00X+016158Y+099567X0200Y    R180 S0      
317P3V3_AUX         VIA   -    MD0100PA00X+019500Y+075250X0200Y         S0      
317P3V3_AUX         VIA   -    MD0100PA00X+019100Y+075650X0200Y         S0      
317P3V3_AUX         VIA   -    MD0100PA00X+019300Y+075450X0200Y         S0      
327P3V3_AUX         R5517 -1   M      A01X+011150Y+076542X0198Y0197R090 S1      
327P3V3_AUX         C2092 -1   M      A01X+011750Y+076858X0198Y0197R270 S1      
327P3V3_AUX         U401  -5          A01X+011706Y+077326X0160Y0200     S1      
317P3V3_AUX         VIA   -    MD0100PA00X+011229Y+075429X0200Y         S0      
327P3V3_AUX         C93   -2   M      A01X+007092Y+075150X0198Y0197R180 S1      
317P3V3_AUX         VIA   -    MD0100PA00X+007092Y+074900X0200Y         S0      
327P3V3_AUX         U59   -8          A01X+005090Y+075050X0220Y0680R270 S1      
317P3V3_AUX         VIA   -    MD0100PA00X+007648Y+074250X0200Y         S0      
327P3V3_AUX         R308  -1          A01X+007408Y+074250X0198Y0197R180 S1      
317P3V3_AUX         VIA   -    MD0100PA00X+011552Y+073800X0200Y         S0      
327P3V3_AUX         R4956 -1          A01X+011792Y+073800X0198Y0197     S1      
317P3V3_AUX         VIA   -    MD0100PA00X+011552Y+073100X0200Y         S0      
327P3V3_AUX         R4957 -1          A01X+011792Y+073100X0198Y0197     S1      
317P3V3_AUX         VIA   -    MD0100PA00X+011552Y+074500X0200Y         S0      
327P3V3_AUX         R4955 -1          A01X+011792Y+074500X0198Y0197     S1      
317P3V3_AUX         VIA   -    MD0100PA00X+013915Y+071250X0200Y         S0      
327P3V3_AUX         U390  -14         A01X+015400Y+072268X0140Y0590R270 S1      
327P3V3_AUX         C188  -1   M      A01X+015208Y+072900X0198Y0197R180 S1      
327P3V3_AUX         R509  -1          A01X+011792Y+071800X0198Y0197     S1      
317P3V3_AUX         VIA   -    MD0100PA00X+011950Y+071550X0200Y         S0      
317P3V3_AUX         VIA   -    MD0100PA00X+007648Y+071500X0200Y         S0      
327P3V3_AUX         R2360 -1          A01X+007408Y+071500X0198Y0197R180 S1      
327P3V3_AUX         R510  -1          A01X+011792Y+071100X0198Y0197     S1      
327P3V3_AUX         R511  -1          A01X+011792Y+070400X0198Y0197     S1      
317P3V3_AUX         VIA   -    MD0100PA00X+011950Y+070750X0200Y         S0      
327P3V3_AUX         R5683 -1          A01X+008358Y+070000X0198Y0197R180 S1      
317P3V3_AUX         VIA   -    MD0100PA00X+008600Y+070000X0200Y         S0      
327P3V3_AUX         R5685 -1          A01X+007408Y+070950X0198Y0197R180 S1      
317P3V3_AUX         VIA   -    MD0100PA00X+007650Y+070950X0200Y         S0      
327P3V3_AUX         R5684 -1          A01X+007408Y+070400X0198Y0197R180 S1      
317P3V3_AUX         VIA   -    MD0100PA00X+007650Y+070400X0200Y         S0      
327P3V3_AUX         R312  -1          A01X+001992Y+074800X0198Y0197     S1      
317P3V3_AUX         VIA   -    MD0100PA00X+001750Y+074800X0200Y         S0      
327P3V3_AUX         R311  -1          A01X+001992Y+074100X0198Y0197     S1      
317P3V3_AUX         VIA   -    MD0100PA00X+001750Y+074100X0200Y         S0      
327P3V3_AUX         R310  -1          A01X+001992Y+073400X0198Y0197     S1      
317P3V3_AUX         VIA   -    MD0100PA00X+001750Y+073400X0200Y         S0      
327P3V3_AUX         R2361 -1          A01X+001342Y+072300X0198Y0197     S1      
327P3V3_AUX         R2356 -1   M      A01X+001342Y+071900X0198Y0197     S1      
317P3V3_AUX         VIA   -    MD0100PA00X+001300Y+070900X0200Y         S0      
327P3V3_AUX         R5672 -1          A01X+008358Y+069200X0198Y0197R180 S1      
327P3V3_AUX         C2010 -1   M      A01X+013142Y+065650X0198Y0197     S1      
327P3V3_AUX         U8    -24         A01X+013150Y+066142X0140Y0590R090 S1      
327P3V3_AUX         R5093 -2          A01X+011242Y+066750X0198Y0197R180 S1      
327P3V3_AUX         R5671 -1          A01X+008358Y+068400X0198Y0197R180 S1      
317P3V3_AUX         VIA   -    MD0100PA00X+008600Y+068400X0200Y         S0      
327P3V3_AUX         R5670 -1          A01X+008358Y+067600X0198Y0197R180 S1      
317P3V3_AUX         VIA   -    MD0100PA00X+008600Y+067600X0200Y         S0      
317P3V3_AUX         VIA   -    MD0100PA00X+005648Y+068500X0200Y    R180 S0      
327P3V3_AUX         R5506 -1          A01X+005408Y+068500X0198Y0197R180 S1      
327P3V3_AUX         C1939 -1          A06X+003742Y+067650X0198Y0197R180 S2      
327P3V3_AUX         C1941 -1          A06X+003742Y+067250X0198Y0197R180 S2      
327P3V3_AUX         C1943 -1          A06X+003742Y+068050X0198Y0197R180 S2      
327P3V3_AUX         C1945 -1          A06X+003742Y+068450X0198Y0197R180 S2      
327P3V3_AUX         C55   -1          A06X+003742Y+066850X0198Y0197R180 S2      
317P3V3_AUX         VIA   -    MD0100PA00X+017550Y+065150X0200Y         S0      
327P3V3_AUX         R5112 -1          A01X+017308Y+065150X0198Y0197R180 S1      
317P3V3_AUX         VIA   -    MD0100PA00X+017600Y+065950X0200Y         S0      
327P3V3_AUX         R5114 -1          A01X+017308Y+066350X0198Y0197R180 S1      
327P3V3_AUX         R5113 -1   M      A01X+017308Y+065950X0198Y0197R180 S1      
317P3V3_AUX         VIA   -    MD0100PA00X+016948Y+072000X0200Y         S0      
327P3V3_AUX         R520  -2          A01X+016708Y+072000X0198Y0197     S1      
317P3V3_AUX         VIA   -    MD0100PA00X+016948Y+071300X0200Y         S0      
327P3V3_AUX         R518  -2          A01X+016708Y+071300X0198Y0197     S1      
317P3V3_AUX         VIA   -    MD0100PA00X+016948Y+070600X0200Y         S0      
327P3V3_AUX         R512  -1          A01X+016708Y+070600X0198Y0197R180 S1      
317P3V3_AUX         VIA   -    MD0100PA00X+016948Y+073300X0200Y         S0      
327P3V3_AUX         R4958 -1          A01X+016708Y+073300X0198Y0197R180 S1      
317P3V3_AUX         VIA   -    MD0100PA00X+016948Y+074000X0200Y         S0      
327P3V3_AUX         R4964 -2          A01X+016708Y+074000X0198Y0197     S1      
317P3V3_AUX         VIA   -    MD0100PA00X+016948Y+074700X0200Y         S0      
327P3V3_AUX         R4966 -2          A01X+016708Y+074700X0198Y0197     S1      
317P3V3_AUX         VIA   -    MD0100PA00X+012850Y+079150X0200Y         S0      
327P3V3_AUX         R5389 -1          A01X+012700Y+079392X0198Y0197R090 S1      
327P3V3_AUX         U389  -14         A01X+015450Y+075368X0140Y0590R270 S1      
317P3V3_AUX         VIA   -    MD0100PA00X+016392Y+075650X0200Y         S0      
327P3V3_AUX         C1953 -1   M      A01X+016392Y+075400X0198Y0197     S1      
327P3V3_AUX         R5512 -1   M      A01X+009150Y+083358X0198Y0197R270 S1      
327P3V3_AUX         C2087 -1   M      A01X+008550Y+083042X0198Y0197R090 S1      
327P3V3_AUX         U62   -5          A01X+008594Y+082574X0160Y0200R180 S1      
317P3V3_AUX         VIA   -    MD0100PA00X+014300Y+084235X0200Y         S0      
317P3V3_AUX         VIA   -    MD0100PA00X+012928Y+078180X0200Y         S0      
327P3V3_AUX         R5391 -1          A01X+012700Y+078092X0198Y0197R090 S1      
317P3V3_AUX         VIA   -    MD0100PA00X+005648Y+066000X0200Y    R180 S0      
327P3V3_AUX         R5510 -1          A01X+005408Y+066000X0198Y0197R180 S1      
327P3V3_AUX         C51   -1          A06X+003749Y+065652X0198Y0197R180 S2      
327P3V3_AUX         C53   -1          A06X+003749Y+066052X0198Y0197R180 S2      
327P3V3_AUX         C57   -1          A06X+003742Y+066450X0198Y0197R180 S2      
327P3V3_AUX         R344  -1   M      A01X+008850Y+081042X0198Y0197R090 S1      
327P3V3_AUX         R5371 -1          A01X+007700Y+081658X0198Y0197R270 S1      
317P3V3_AUX         VIA   -    MD0100PA00X+007700Y+081900X0200Y    R180 S0      
327P3V3_AUX         C1502 -1   M      A01X+007092Y+072900X0198Y0197     S1      
327P3V3_AUX         R5486 -1          A01X+003758Y+072750X0198Y0197R180 S1      
327P3V3_AUX         R4856 -1   M      A01X+002392Y+067250X0198Y0197     S1      
327P3V3_AUX         R4860 -1          A01X+002392Y+068050X0198Y0197     S1      
327P3V3_AUX         R4864 -1          A01X+002392Y+068600X0198Y0197     S1      
327P3V3_AUX         U7    -24  M      A01X+005200Y+072258X0140Y0590R270 S1      
317P3V3_AUX         VIA   -    MD0100PA00X+007092Y+073200X0200Y         S0      
327P3V3_AUX         U26   -5   M      A01X+003526Y+068200X0160Y0200R090 S1      
317P3V3_AUX         VIA   -    MD0100PA00X+003276Y+068200X0200Y    R180 S0      
317P3V3_AUX         VIA   -    MD0100PA00X+002152Y+067250X0200Y    R180 S0      
317P3V3_AUX         VIA   -    MD0100PA00X+006150Y+072850X0200Y         S0      
327P3V3_AUX         U25   -5          A01X+003526Y+066950X0160Y0200R090 S1      
317P3V3_AUX         VIA   -    MD0100PA00X+003276Y+066950X0200Y    R180 S0      
327P3V3_AUX         R101  -1          A01X+002392Y+065400X0198Y0197     S1      
317P3V3_AUX         VIA   -    MD0100PA00X+002152Y+065400X0200Y    R180 S0      
327P3V3_AUX         R102  -1          A01X+002392Y+066000X0198Y0197     S1      
317P3V3_AUX         VIA   -    MD0100PA00X+002152Y+066000X0200Y    R180 S0      
327P3V3_AUX         U24   -5          A01X+003526Y+065700X0160Y0200R090 S1      
317P3V3_AUX         VIA   -    MD0100PA00X+003276Y+065700X0200Y    R180 S0      
327P3V3_AUX         R4852 -1          A01X+002392Y+066650X0198Y0197     S1      
317P3V3_AUX         VIA   -    MD0100PA00X+002152Y+066650X0200Y    R180 S0      
327P3V3_AUX         R99   -1   M      A01X+002392Y+064550X0198Y0197     S1      
327P3V3_AUX         R98   -1          A01X+002392Y+064100X0198Y0197     S1      
317P3V3_AUX         VIA   -    MD0100PA00X+002100Y+064400X0200Y         S0      
327P3V3_AUX         R5521 -1          A01X+011450Y+078858X0198Y0197R270 S1      
317P3V3_AUX         VIA   -    MD0100PA00X+007150Y+080550X0200Y    R180 S0      
327P3V3_AUX         R5370 -1          A01X+007700Y+080358X0198Y0197R270 S1      
327P3V3_AUX         U23   -5          A01X+003526Y+064600X0160Y0200R090 S1      
317P3V3_AUX         VIA   -    MD0100PA00X+003226Y+064600X0200Y         S0      
327P3V3_AUX         R5504 -1          A01X+005408Y+067250X0198Y0197R180 S1      
317P3V3_AUX         VIA   -    M      A01X+005648Y+067250X0200Y    R180 S2      
017P3V3_AUX         VIA   -    M      A06X+005648Y+067250X0260Y    R180 S2      
017P3V3_AUX               -    MD0100PA00X+005648Y+067250                       
327P3V3_AUX         R5505 -1          A01X+005408Y+067900X0198Y0197R180 S1      
317P3V3_AUX         VIA   -    MD0100PA00X+005648Y+067900X0200Y    R180 S0      
327P3V3_AUX         R5503 -1          A01X+005408Y+066650X0198Y0197R180 S1      
317P3V3_AUX         VIA   -    MD0100PA00X+005648Y+066650X0200Y    R180 S0      
317P3V3_AUX         VIA   -    MD0100PA00X+005648Y+064700X0200Y    R180 S0      
327P3V3_AUX         R5508 -1          A01X+005408Y+064700X0198Y0197R180 S1      
327P3V3_AUX         R5507 -1          A01X+005408Y+064100X0198Y0197R180 S1      
317P3V3_AUX         VIA   -    MD0100PA00X+005648Y+064100X0200Y    R180 S0      
317P3V3_AUX         VIA   -    M      A01X+005648Y+065400X0200Y    R180 S2      
017P3V3_AUX         VIA   -    M      A06X+005648Y+065400X0260Y    R180 S2      
017P3V3_AUX               -    MD0100PA00X+005648Y+065400                       
327P3V3_AUX         R5509 -1          A01X+005408Y+065400X0198Y0197R180 S1      
327P3V3_AUX         C1933 -2   M      A01X+007850Y+060842X0198Y0197R270 S1      
327P3V3_AUX         U321  -24         A01X+008342Y+061000X0140Y0590     S1      
317P3V3_AUX         VIA   -    MD0100PA00X+007400Y+060842X0200Y    R090 S0      
327P3V3_AUX         R5278 -2   M      A01X+010750Y+055592X0198Y0197R270 S1      
327P3V3_AUX         R5281 -2   M      A01X+011450Y+055592X0198Y0197R270 S1      
327P3V3_AUX         R5280 -2   M      A01X+012450Y+055492X0198Y0197R270 S1      
327P3V3_AUX         R5283 -2   M      A01X+013150Y+055492X0198Y0197R270 S1      
317P3V3_AUX         VIA   -    MD0100PA00X+011100Y+055592X0200Y         S0      
317P3V3_AUX         VIA   -    MD0100PA00X+012850Y+055492X0200Y         S0      
327P3V3_AUX         R5279 -2   M      A01X+010100Y+055592X0198Y0197R270 S1      
317P3V3_AUX         VIA   -    MD0100PA00X+008405Y+055592X0200Y         S0      
327P3V3_AUX         R5277 -2   M      A01X+009100Y+055592X0198Y0197R270 S1      
327P3V3_AUX         R5276 -2   M      A01X+009550Y+055592X0198Y0197R270 S1      
327P3V3_AUX         R5282 -2   M      A01X+013550Y+055492X0198Y0197R270 S1      
327P3V3_AUX         R5270 -2   M      A01X+011400Y+064308X0198Y0197R090 S1      
327P3V3_AUX         R5271 -2   M      A01X+012100Y+064308X0198Y0197R090 S1      
327P3V3_AUX         R5272 -2   M      A01X+009850Y+064308X0198Y0197R090 S1      
327P3V3_AUX         R5273 -2   M      A01X+010700Y+064308X0198Y0197R090 S1      
327P3V3_AUX         R5269 -2   M      A01X+013850Y+064308X0198Y0197R090 S1      
327P3V3_AUX         R5288 -2   M      A01X+012650Y+064308X0198Y0197R090 S1      
327P3V3_AUX         R5275 -2   M      A01X+009250Y+064308X0198Y0197R090 S1      
327P3V3_AUX         R5274 -2   M      A01X+008470Y+064308X0198Y0197R090 S1      
327P3V3_AUX         R5472 -1          A01X+008080Y+064308X0198Y0197R270 S1      
327P3V3_AUX         R572  -2          A01X+008000Y+055592X0198Y0197R270 S1      
327P3V3_AUX         R5473 -1   M      A01X+007500Y+057342X0198Y0197R090 S1      
327P3V3_AUX         R5523 -1          A01X+006800Y+057342X0198Y0197R090 S1      
317P3V3_AUX         VIA   -    MD0100PA00X+007375Y+057072X0200Y    R090 S0      
327P3V3_AUX         U403  -21         A01X+017398Y+052607X0110Y0360     S1      
327P3V3_AUX         C2094 -2   M      A01X+017650Y+053192X0198Y0197R270 S1      
317P3V3_AUX         VIA   -    MD0100PA00X+017900Y+053192X0200Y         S0      
327P3V3_AUX         R5562 -1          A01X+016650Y+053508X0198Y0197R270 S1      
327P3V3_AUX         R5561 -1          A01X+017150Y+053508X0198Y0197R270 S1      
317P3V3_AUX         VIA   -    MD0100PA00X+016900Y+053508X0200Y         S0      
327P3V3_AUX         R4947 -2          A01X+009300Y+052908X0198Y0197R090 S1      
317P3V3_AUX         VIA   -    MD0100PA00X+009300Y+053148X0200Y         S0      
317P3V3_AUX         VIA   -    MD0100PA00X+008750Y+053148X0200Y         S0      
327P3V3_AUX         R4946 -2          A01X+008750Y+052908X0198Y0197R090 S1      
317P3V3_AUX         VIA   -    MD0100PA00X+008200Y+053148X0200Y         S0      
327P3V3_AUX         R4849 -1          A01X+008200Y+052908X0198Y0197R270 S1      
327P3V3_AUX         R5682 -1          A01X+009892Y+053150X0198Y0197     S1      
317P3V3_AUX         VIA   -    MD0100PA00X+009892Y+053400X0200Y         S0      
317P3V3_AUX         VIA   -    MD0100PA00X+007650Y+053148X0200Y         S0      
327P3V3_AUX         R4848 -1   M      A01X+007650Y+052908X0198Y0197R270 S1      
327P3V3_AUX         R4945 -2          A01X+007100Y+052908X0198Y0197R090 S1      
317P3V3_AUX         VIA   -    MD0100PA00X+014977Y+028329X0200Y         S0      
327P3V3_AUX         U381  -5          A06X+015357Y+028329X0130Y0460R090 S2      
327P3V3_AUX         C2069 -1          A01X+015278Y+028273X0198Y0197     S1      
317P3V3_AUX         VIA   -    MD0100PA00X+017881Y+028107X0200Y         S0      
327P3V3_AUX         U396  -5          A06X+017881Y+028377X0240Y0240R270 S2      
327P3V3_AUX         C2068 -1          A01X+017586Y+028230X0198Y0197R270 S1      
327P3V3_AUX         C165  -1          A01X+013648Y+026415X0198Y0197R090 S1      
327P3V3_AUX         U391  -5          A06X+013353Y+026268X0240Y0240R090 S2      
317P3V3_AUX         VIA   -    MD0100PA00X+013353Y+026538X0200Y    R180 S0      
317P3V3_AUX         VIA   -    MD0100PA00X+016110Y+026608X0200Y    R180 S0      
327P3V3_AUX         U74   -5          A06X+015877Y+026317X0130Y0460R270 S2      
327P3V3_AUX         C172  -1          A01X+015956Y+026373X0198Y0197R180 S1      
327P3V3_AUX         C2062 -1          A01X+006656Y+028230X0198Y0197R270 S1      
327P3V3_AUX         U393  -5          A06X+006951Y+028377X0240Y0240R270 S2      
317P3V3_AUX         VIA   -    MD0100PA00X+007250Y+028377X0200Y         S0      
327P3V3_AUX         C2063 -1          A01X+004349Y+028273X0198Y0197     S1      
327P3V3_AUX         U361  -5          A06X+004427Y+028329X0130Y0460R090 S2      
317P3V3_AUX         VIA   -    MD0100PA00X+004047Y+028329X0200Y         S0      
327P3V3_AUX         U392  -5          A06X+001205Y+026396X0240Y0240R090 S2      
317P3V3_AUX         VIA   -    MD0100PA00X+001279Y+026100X0200Y    R180 S0      
327P3V3_AUX         C2060 -1          A01X+001279Y+026415X0198Y0197R090 S1      
317P3V3_AUX         VIA   -    MD0100PA00X+003888Y+026317X0200Y    R180 S0      
327P3V3_AUX         U359  -5          A06X+003508Y+026317X0130Y0460R270 S2      
327P3V3_AUX         C2061 -1          A01X+003587Y+026373X0198Y0197R180 S1      
327P3V3_AUX         R5565 -1          A01X+002700Y+053408X0198Y0197R270 S1      
317P3V3_AUX         VIA   -    MD0100PA00X+002950Y+053408X0200Y         S0      
327P3V3_AUX         R5559 -1          A01X+019158Y+051550X0198Y0197R180 S1      
317P3V3_AUX         VIA   -    MD0100PA00X+018950Y+051200X0200Y         S0      
317P3V3_AUX         VIA   -    MD0100PA00X+011350Y+052300X0200Y         S0      
327P3V3_AUX         C1932 -2   M      A01X+011600Y+052392X0198Y0197R270 S1      
327P3V3_AUX         U317  -21         A01X+011928Y+051637X0070Y0320R180 S1      
327P3V3_AUX         R4941 -2          A01X+009892Y+051750X0198Y0197R180 S1      
317P3V3_AUX         VIA   -    MD0100PA00X+009892Y+051500X0200Y         S0      
327P3V3_AUX         U404  -21         A01X+002543Y+051748X0110Y0360R090 S1      
317P3V3_AUX         VIA   -    MD0100PA00X+001099Y+052342X0200Y         S0      
327P3V3_AUX         C2095 -2   M      A01X+001658Y+052000X0198Y0197     S1      
327P3V3_AUX         R5566 -1          A01X+001342Y+051100X0198Y0197     S1      
317P3V3_AUX         VIA   -    MD0100PA00X+001100Y+051100X0200Y         S0      
327P3V3_AUX         R4778 -1          A01X+013000Y+048742X0198Y0197R090 S1      
317P3V3_AUX         VIA   -    MD0100PA00X+013000Y+048502X0200Y         S0      
327P3V3_AUX         R4937 -2          A01X+013550Y+048742X0198Y0197R270 S1      
317P3V3_AUX         VIA   -    MD0100PA00X+013550Y+048502X0200Y         S0      
327P3V3_AUX         R4948 -2          A01X+010208Y+049350X0198Y0197     S1      
317P3V3_AUX         VIA   -    MD0100PA00X+010576Y+049350X0200Y         S0      
327P3V3_AUX         R4943 -2   M      A01X+010650Y+050042X0198Y0197R270 S1      
327P3V3_AUX         R4949 -2          A01X+010208Y+050350X0198Y0197     S1      
317P3V3_AUX         VIA   -    MD0100PA00X+010900Y+050000X0200Y         S0      
327P3V3_AUX         R4939 -2          A01X+011350Y+048742X0198Y0197R270 S1      
317P3V3_AUX         VIA   -    MD0100PA00X+011350Y+048500X0200Y         S0      
327P3V3_AUX         R4938 -2          A01X+011900Y+048742X0198Y0197R270 S1      
317P3V3_AUX         VIA   -    MD0100PA00X+011900Y+048500X0200Y         S0      
327P3V3_AUX         R4779 -1          A01X+012450Y+048742X0198Y0197R090 S1      
317P3V3_AUX         VIA   -    MD0100PA00X+012450Y+048500X0200Y         S0      
327P3V3_AUX         R5567 -1          A01X+001342Y+050200X0198Y0197     S1      
317P3V3_AUX         VIA   -    MD0100PA00X+001100Y+050200X0200Y         S0      
327P3V3_AUX         U330  -21         A01X+008722Y+050063X0070Y0320     S1      
327P3V3_AUX         C1938 -2   M      A01X+008750Y+048708X0198Y0197R090 S1      
327P3V3_AUX         R352  -1          A01X+008542Y+045050X0198Y0197     S1      
327P3V3_AUX         R5513 -1   M      A01X+009150Y+047058X0198Y0197R270 S1      
327P3V3_AUX         C2088 -1   M      A01X+008550Y+046742X0198Y0197R090 S1      
327P3V3_AUX         R5363 -1   M      A01X+007700Y+045308X0198Y0197R270 S1      
327P3V3_AUX         U64   -5   M      A01X+008594Y+046274X0160Y0200R180 S1      
317P3V3_AUX         VIA   -    MD0100PA00X+011050Y+044500X0200Y         S0      
327P3V3_AUX         R5393 -1   M      A01X+012750Y+041842X0198Y0197R090 S1      
327P3V3_AUX         R5516 -1          A01X+010950Y+040042X0198Y0197R090 S1      
327P3V3_AUX         R5520 -1   M      A01X+011500Y+042358X0198Y0197R270 S1      
327P3V3_AUX         C2091 -1          A01X+011350Y+040358X0198Y0197R270 S1      
327P3V3_AUX         R5362 -1          A01X+007700Y+043558X0198Y0197R270 S1      
317P3V3_AUX         VIA   -    MD0100PA00X+010700Y+040042X0200Y    R270 S0      
327P3V3_AUX         U400  -5   M      A01X+011756Y+040826X0160Y0200     S1      
327P3V3_AUX         R5399 -1          A01X+012442Y+043500X0198Y0197     S1      
317P3V3_AUX         VIA   -    MD0100PA00X+008458Y+048708X0200Y         S0      
327P3V3_AUX         R5681 -1          A01X+010900Y+047842X0198Y0197R090 S1      
327P3V3_AUX         U66   -5   M      A01X+008594Y+010474X0160Y0200R180 S1      
327P3V3_AUX         R4992 -1          A01X+007700Y+009008X0198Y0197R270 S1      
327P3V3_AUX         R4990 -1          A01X+007700Y+010758X0198Y0197R270 S1      
327P3V3_AUX         C2089 -1   M      A01X+008550Y+010942X0198Y0197R090 S1      
327P3V3_AUX         R5514 -1          A01X+009150Y+011258X0198Y0197R270 S1      
327P3V3_AUX         C2090 -1   M      A01X+012192Y+006650X0198Y0197     S1      
327P3V3_AUX         U399  -5   M      A01X+011856Y+007126X0160Y0200     S1      
327P3V3_AUX         R5397 -1          A01X+012700Y+008542X0198Y0197R090 S1      
327P3V3_AUX         R5515 -1          A01X+010766Y+008155X0198Y0197R180 S1      
327P3V3_AUX         R5519 -1   M      A01X+011292Y+008350X0198Y0197     S1      
327FAN_7_FAULT_R    PR72  -1          A01X+006350Y+101642X0180Y0200R270 S1      
327FAN_7_FAULT_R    PR71  -1          A01X+005958Y+101600X0198Y0197R180 S1      
327m0201            R5467 -2          A01X+007092Y+071900X0198Y0197R180 S1      
317m0201            VIA   -    M      A01X+006810Y+072100X0200Y         S2      
017m0201            VIA   -    M      A06X+006810Y+072100X0260Y         S2      
017m0201                  -    MD0100PA00X+006810Y+072100                       
327m0201            U7    -22         A01X+005200Y+071746X0140Y0590R270 S1      
327SMB_FAN6_SCL     R5223 -1          A01X+005808Y+078811X0198Y0197R180 S1      
317SMB_FAN6_SCL     VIA   -    MD0100PA00X+009928Y+078194X0200Y         S0      
327SMB_FAN6_SCL     R4879 -2          A01X+009850Y+063158X0198Y0197R090 S1      
317SMB_FAN6_SCL     VIA   -    M      A01X+009905Y+063505X0200Y    R090 S2      
017SMB_FAN6_SCL     VIA   -    M      A06X+009905Y+063505X0260Y    R090 S2      
017SMB_FAN6_SCL           -    MD0100PA00X+009905Y+063505                       
327SMB_FAN0_R_SDA   R4785 -1   M      A01X+008500Y+056808X0198Y0197R270 S1      
327SMB_FAN0_R_SDA   VIA   -    M      A01X+008961Y+058002X0300Y         S1      
327SMB_FAN0_R_SDA   U321  -4          A01X+009110Y+058700X0140Y0590     S1      
327SMB_FAN0_R_SDA   R5277 -1          A01X+009100Y+055908X0198Y0197R270 S1      
327FAN_7_SS         PC58  -1          A06X+006856Y+101958X0198Y0197R090 S2      
317FAN_7_SS         VIA   -    M      A01X+006600Y+102500X0300Y         S1      
017FAN_7_SS         VIA   -    M      A06X+006600Y+102500X0200Y         S1      
017FAN_7_SS               -    MD0100PA00X+006600Y+102500                       
327FAN_7_SS         PU9   -21         A06X+006214Y+103171X0070Y0360R180 S2      
327FAN_7_MODE       PR73  -2          A01X+005958Y+102000X0198Y0197     S1      
327FAN_7_MODE       PR75  -1   M      A01X+005958Y+102400X0198Y0197R180 S1      
317FAN_7_MODE       VIA   -    M      A01X+004410Y+102785X0300Y         S1      
017FAN_7_MODE       VIA   -    M      A06X+004410Y+102785X0200Y         S1      
017FAN_7_MODE             -    MD0100PA00X+004410Y+102785                       
327FAN_7_MODE       PU9   -30         A06X+004796Y+103171X0276Y0354R180 S2      
317m0202            VIA   -    M      A01X+006307Y+065240X0200Y         S2      
017m0202            VIA   -    M      A06X+006307Y+065240X0260Y         S2      
017m0202                  -    MD0100PA00X+006307Y+065240                       
327m0202            R5509 -2   M      A01X+005092Y+065400X0198Y0197R180 S1      
327m0202            R5497 -2          A01X+006892Y+065150X0198Y0197R180 S1      
327m0202            C56   -1   M      A01X+005992Y+065540X0198Y0197     S1      
327m0202            U24   -1          A01X+004274Y+065444X0160Y0200R090 S1      
327m0203            R5466 -2          A01X+007092Y+072400X0198Y0197R180 S1      
327m0203            VIA   -    M      A01X+006510Y+072520X0300Y         S1      
327m0203            U7    -23         A01X+005200Y+072002X0140Y0590R270 S1      
317FAN_7_TEMP       VIA   -    M      A01X+004200Y+102300X0300Y         S1      
017FAN_7_TEMP       VIA   -    M      A06X+004200Y+102300X0200Y         S1      
017FAN_7_TEMP             -    MD0100PA00X+004200Y+102300                       
327FAN_7_TEMP       PU9   -29         A06X+004954Y+103171X0070Y0360R180 S2      
327FAN_7_TEMP       PC2125-1          A06X+003806Y+101954X0198Y0197R090 S2      
327FAN_7_TEMP       PR76  -1   M      A06X+004212Y+101954X0198Y0197R090 S2      
317m0204            VIA   -    M      A01X+003272Y+066000X0200Y         S2      
017m0204            VIA   -    M      A06X+003272Y+066000X0260Y         S2      
017m0204                  -    MD0100PA00X+003272Y+066000                       
327m0204            R102  -2   M      A01X+002708Y+066000X0198Y0197     S1      
327m0204            R105  -1          A01X+001808Y+066000X0198Y0197R180 S1      
327m0204            U24   -4          A01X+003526Y+065956X0160Y0200R090 S1      
327FAN_0_PWM_IL_R   VIA   -    M      A01X+015700Y+118250X0300Y         S1      
317FAN_0_PWM_IL_R   J1    -3    D0380PA00X+017716Y+118626X0540Y    R090 S3      
327FAN_0_PWM_IL_R   C2021 -1   M      A01X+013850Y+118042X0198Y0197R090 S1      
327FAN_0_PWM_IL_R   R5186 -1   M      A01X+014858Y+117850X0198Y0197R180 S1      
327FAN_0_PWM_IL_R   D268  -C          A01X+013167Y+117850X0220Y0240R180 S1      
327m0205            R5510 -2   M      A01X+005092Y+066000X0198Y0197R180 S1      
327m0205            R5498 -2          A01X+006892Y+065750X0198Y0197R180 S1      
327m0205            C58   -1   M      A01X+005992Y+066000X0198Y0197     S1      
317m0205            VIA   -    M      A01X+005298Y+066265X0200Y         S2      
017m0205            VIA   -    M      A06X+005298Y+066265X0260Y         S2      
017m0205                  -    MD0100PA00X+005298Y+066265                       
327m0205            U24   -3          A01X+004274Y+065956X0160Y0200R090 S1      
317SMB_FAN5_SDA     VIA   -    M      A01X+011808Y+063995X0200Y    R090 S2      
017SMB_FAN5_SDA     VIA   -    M      A06X+011808Y+063995X0260Y    R090 S2      
017SMB_FAN5_SDA           -    MD0100PA00X+011808Y+063995                       
327SMB_FAN5_SDA     R4878 -2          A01X+012100Y+063158X0198Y0197R090 S1      
327SMB_FAN5_SDA     R5205 -2          A01X+005808Y+042923X0198Y0197     S1      
317SMB_FAN5_SDA     VIA   -    MD0100PA00X+006048Y+042923X0200Y         S0      
327FAN_7_CS         PR74  -1          A06X+007656Y+101958X0198Y0197R090 S2      
317FAN_7_CS         VIA   -    M      A01X+007400Y+102600X0300Y         S1      
017FAN_7_CS         VIA   -    M      A06X+007400Y+102600X0200Y         S1      
017FAN_7_CS               -    MD0100PA00X+007400Y+102600                       
327FAN_7_CS         PU9   -19         A06X+006528Y+103171X0276Y0354R180 S2      
317m0206            J1    -4    D0380PA00X+016929Y+118626X0540Y    R090 S3      
327m0206            R5495 -1          A01X+007208Y+064100X0198Y0197R180 S1      
317m0206            VIA   -    M      A01X+015030Y+064590X0200Y         S2      
017m0206            VIA   -    M      A06X+015030Y+064590X0260Y         S2      
017m0206                  -    MD0100PA00X+015030Y+064590                       
327FAN_7_CLREF      VIA   -    M      A06X+005726Y+102402X0260Y         S2      
327FAN_7_CLREF      PC3125-2   M      A06X+005650Y+101958X0198Y0197R270 S2      
327FAN_7_CLREF      PU9   -24         A06X+005741Y+103171X0070Y0360R180 S2      
327FAN_7_CLREF      PR77  -1          A06X+006050Y+101958X0198Y0197R090 S2      
327m0207            R5508 -2   M      A01X+005092Y+064700X0198Y0197R180 S1      
327m0207            R5496 -2          A01X+006892Y+064700X0198Y0197R180 S1      
327m0207            C54   -1   M      A01X+005992Y+064700X0198Y0197     S1      
317m0207            VIA   -    M      A01X+004750Y+064900X0200Y         S2      
017m0207            VIA   -    M      A06X+004750Y+064900X0260Y         S2      
017m0207                  -    MD0100PA00X+004750Y+064900                       
327m0207            U23   -3          A01X+004274Y+064856X0160Y0200R090 S1      
327SMB_FAN5_SCL     R4877 -2          A01X+011400Y+063158X0198Y0197R090 S1      
317SMB_FAN5_SCL     VIA   -    M      A01X+010860Y+062708X0200Y    R090 S2      
017SMB_FAN5_SCL     VIA   -    M      A06X+010860Y+062708X0260Y    R090 S2      
017SMB_FAN5_SCL           -    MD0100PA00X+010860Y+062708                       
317SMB_FAN5_SCL     VIA   -    MD0100PA00X+006048Y+042473X0200Y         S0      
327SMB_FAN5_SCL     R5203 -1          A01X+005808Y+042473X0198Y0197R180 S1      
327m0208            R101  -2   M      A01X+002708Y+065400X0198Y0197     S1      
327m0208            R104  -1          A01X+001808Y+065400X0198Y0197R180 S1      
327m0208            U24   -6          A01X+003526Y+065444X0160Y0200R090 S1      
327SMB_FAN4_SDA     R5132 -2          A01X+005808Y+008419X0198Y0197     S1      
317SMB_FAN4_SDA     VIA   -    M      A01X+006100Y+008419X0200Y         S2      
017SMB_FAN4_SDA     VIA   -    M      A06X+006100Y+008419X0260Y         S2      
017SMB_FAN4_SDA           -    MD0100PA00X+006100Y+008419                       
317SMB_FAN4_SDA     VIA   -    MD0100PA00X+013500Y+063750X0200Y    R090 S0      
327SMB_FAN4_SDA     R4876 -2          A01X+013500Y+063158X0198Y0197R090 S1      
317FAN_4_TEMP       VIA   -    M      A01X+004231Y+025127X0300Y         S1      
017FAN_4_TEMP       VIA   -    M      A06X+004231Y+025127X0200Y         S1      
017FAN_4_TEMP             -    MD0100PA00X+004231Y+025127                       
327FAN_4_TEMP       PU6   -29         A06X+003032Y+024152X0070Y0360     S2      
327FAN_4_TEMP       PC2122-1          A06X+004231Y+025369X0198Y0197R270 S2      
327FAN_4_TEMP       PR52  -1   M      A06X+003823Y+025369X0198Y0197R270 S2      
317m0209            VIA   -    M      A01X+003038Y+064832X0200Y         S2      
017m0209            VIA   -    M      A06X+003038Y+064832X0260Y         S2      
017m0209                  -    MD0100PA00X+003038Y+064832                       
327m0209            R103  -1          A01X+001808Y+064550X0198Y0197R180 S1      
327m0209            U23   -4          A01X+003526Y+064856X0160Y0200R090 S1      
327m0209            R99   -2          A01X+002708Y+064550X0198Y0197     S1      
327FAN_7_PWM_OL     R5238 -1          A01X+005762Y+112865X0198Y0197R180 S1      
327FAN_7_PWM_OL     VIA   -    M      A01X+008200Y+112350X0300Y         S1      
327FAN_7_PWM_OL     U329  -2          A01X+009776Y+113694X0280Y0360R090 S1      
327FAN_4_MODE       PU6   -30         A06X+003189Y+024152X0276Y0354     S2      
317FAN_4_MODE       VIA   -    M      A01X+003688Y+024922X0300Y    R180 S1      
017FAN_4_MODE       VIA   -    M      A06X+003688Y+024922X0200Y    R180 S1      
017FAN_4_MODE             -    MD0100PA00X+003688Y+024922                       
327FAN_4_MODE       PR49  -2          A01X+002642Y+025550X0198Y0197R180 S1      
327FAN_4_MODE       PR51  -1   M      A01X+002558Y+025150X0198Y0197R180 S1      
327m0210            VIA   -    M      A01X+006448Y+063622X0300Y         S1      
327m0210            R5507 -2   M      A01X+005092Y+064100X0198Y0197R180 S1      
327m0210            R5495 -2          A01X+006892Y+064100X0198Y0197R180 S1      
327m0210            C52   -1   M      A01X+005992Y+064100X0198Y0197     S1      
327m0210            U23   -1          A01X+004274Y+064344X0160Y0200R090 S1      
327SMB_FAN4_SCL     R5131 -1          A01X+005808Y+007969X0198Y0197R180 S1      
317SMB_FAN4_SCL     VIA   -    MD0100PA00X+006048Y+007969X0200Y         S0      
317SMB_FAN4_SCL     VIA   -    M      A01X+013150Y+063450X0200Y         S2      
017SMB_FAN4_SCL     VIA   -    M      A06X+013150Y+063450X0260Y         S2      
017SMB_FAN4_SCL           -    MD0100PA00X+013150Y+063450                       
327SMB_FAN4_SCL     R4874 -2          A01X+013100Y+063158X0198Y0197R090 S1      
327FAN_4_FAULT_R    PR48  -1          A01X+002250Y+025858X0180Y0200R090 S1      
327FAN_4_FAULT_R    PR47  -1          A01X+002642Y+025950X0198Y0197     S1      
327FAN_4_FAULT_R    VIA   -    M      A01X+002799Y+026464X0300Y         S1      
327FAN_7_PWM_IL     R5241 -2          A01X+005812Y+114765X0198Y0197     S1      
327FAN_7_PWM_IL     VIA   -    M      A01X+008000Y+115150X0300Y         S1      
327FAN_7_PWM_IL     U329  -1          A01X+009776Y+114206X0280Y0360R090 S1      
327FAN_4_IMON       PR54  -2          A06X+001100Y+025369X0198Y0197R090 S2      
327FAN_4_IMON       PU6   -20         A06X+001614Y+024152X0070Y0360     S2      
327FAN_4_IMON       VIA   -    M      A06X+001029Y+024917X0260Y    R180 S2      
317m0211            VIA   -    M      A01X+006834Y+053326X0200Y         S2      
017m0211            VIA   -    M      A06X+006834Y+053326X0260Y         S2      
017m0211                  -    MD0100PA00X+006834Y+053326                       
327m0211            R4950 -2          A01X+007100Y+053392X0198Y0197R270 S1      
327m0211            R4945 -1   M      A01X+007100Y+052592X0198Y0197R090 S1      
327m0211            U330  -5          A01X+008092Y+051637X0070Y0320     S1      
327FAN_4_P5V        PC39  -1          A06X+003423Y+025369X0198Y0197R270 S2      
327FAN_4_P5V        PU6   -28         A06X+002874Y+024152X0070Y0360     S2      
327FAN_4_P5V        VIA   -    M      A06X+003166Y+024904X0260Y    R180 S2      
327FAN_6_PWM_OL     U327  -2          A01X+009576Y+077344X0280Y0360R090 S1      
327FAN_6_PWM_OL     R5218 -1          A01X+005762Y+076476X0198Y0197R180 S1      
317FAN_6_PWM_OL     VIA   -    M      A01X+006158Y+076220X0200Y         S2      
017FAN_6_PWM_OL     VIA   -    M      A06X+006158Y+076220X0260Y         S2      
017FAN_6_PWM_OL           -    MD0100PA00X+006158Y+076220                       
317m0212            VIA   -    M      A01X+008750Y+052280X0200Y         S2      
017m0212            VIA   -    M      A06X+008750Y+052280X0260Y         S2      
017m0212                  -    MD0100PA00X+008750Y+052280                       
327m0212            R4951 -2          A01X+008750Y+053392X0198Y0197R270 S1      
327m0212            R4946 -1   M      A01X+008750Y+052592X0198Y0197R090 S1      
327m0212            U330  -2          A01X+008565Y+051637X0070Y0320     S1      
327FAN_4_P3V_R      PC38  -1          A06X+003000Y+025369X0198Y0197R270 S2      
327FAN_4_P3V_R      PU6   -27         A06X+002717Y+024152X0070Y0360     S2      
317FAN_4_P3V_R      VIA   -    M      A01X+002939Y+024696X0300Y    R180 S1      
017FAN_4_P3V_R      VIA   -    M      A06X+002939Y+024696X0200Y    R180 S1      
017FAN_4_P3V_R            -    MD0100PA00X+002939Y+024696                       
327FAN_4_P3V_R      PR47  -2          A01X+002958Y+025950X0198Y0197     S1      
327FAN_4_P3V_R      PR49  -1   M      A01X+002958Y+025550X0198Y0197R180 S1      
327m0213            VIA   -    M      A01X+002107Y+063605X0300Y         S1      
327m0213            R98   -2   M      A01X+002708Y+064100X0198Y0197     S1      
327m0213            R100  -1          A01X+001808Y+064100X0198Y0197R180 S1      
327m0213            U23   -6          A01X+003526Y+064344X0160Y0200R090 S1      
327m0214            VIA   -    M      A01X+009099Y+052124X0300Y         S1      
327m0214            R4952 -2          A01X+009300Y+053392X0198Y0197R270 S1      
327m0214            R4947 -1   M      A01X+009300Y+052592X0198Y0197R090 S1      
327m0214            U330  -1          A01X+008722Y+051637X0070Y0320     S1      
327FAN_4_CS         PR50  -1          A06X+000700Y+025365X0198Y0197R270 S2      
317FAN_4_CS         VIA   -    M      A01X+000940Y+024152X0300Y         S1      
017FAN_4_CS         VIA   -    M      A06X+000940Y+024152X0200Y         S1      
017FAN_4_CS               -    MD0100PA00X+000940Y+024152                       
327FAN_4_CS         PU6   -19         A06X+001457Y+024152X0276Y0354     S2      
327FAN_6_PWM_IL     R5221 -2          A01X+005812Y+078376X0198Y0197     S1      
327FAN_6_PWM_IL     VIA   -    M      A01X+008150Y+078900X0300Y         S1      
327FAN_6_PWM_IL     U327  -1          A01X+009576Y+077856X0280Y0360R090 S1      
317m0215            VIA   -    M      A01X+009650Y+050193X0200Y         S2      
017m0215            VIA   -    M      A06X+009650Y+050193X0260Y         S2      
017m0215                  -    MD0100PA00X+009650Y+050193                       
327m0215            R4953 -2          A01X+009892Y+048850X0198Y0197R180 S1      
327m0215            R4948 -1   M      A01X+009892Y+049350X0198Y0197     S1      
327m0215            U330  -25         A01X+009037Y+050850X0070Y0320R270 S1      
317m0216            VIA   -    M      A01X+009804Y+050673X0200Y         S2      
017m0216            VIA   -    M      A06X+009804Y+050673X0260Y         S2      
017m0216                  -    MD0100PA00X+009804Y+050673                       
327m0216            R4954 -2          A01X+009892Y+049850X0198Y0197R180 S1      
327m0216            R4949 -1   M      A01X+009892Y+050350X0198Y0197     S1      
327m0216            U330  -26         A01X+009037Y+051008X0070Y0320R270 S1      
327FAN_4_TIMER      VIA   -    M      A06X+002065Y+024851X0260Y         S2      
327FAN_4_TIMER      PC41  -1          A06X+001900Y+025369X0198Y0197R270 S2      
327FAN_4_TIMER      PU6   -23         A06X+002087Y+024152X0070Y0360     S2      
327FAN_5_PWM_OL     VIA   -    M      A01X+008917Y+040135X0300Y         S1      
327FAN_5_PWM_OL     U325  -2          A01X+009626Y+040844X0280Y0360R090 S1      
327FAN_5_PWM_OL     R5198 -1          A01X+005762Y+040138X0198Y0197R180 S1      
327m0217            VIA   -    M      A01X+012937Y+049523X0300Y         S1      
327m0217            U317  -5          A01X+012558Y+050063X0070Y0320R180 S1      
327m0217            R4937 -1   M      A01X+013550Y+049058X0198Y0197R270 S1      
327m0217            R4935 -2          A01X+013550Y+048158X0198Y0197R090 S1      
327FAN_4_FAULT      PR48  -2          A01X+002250Y+025542X0180Y0200R090 S1      
327FAN_4_FAULT      VIA   -    M      A01X+001687Y+025702X0300Y         S1      
317FAN_4_FAULT      VIA   -    MD0100PA00X+001778Y+024815X0200Y         S0      
327FAN_4_FAULT      PU6   -22         A06X+001929Y+024152X0070Y0360     S2      
317m0218            VIA   -    M      A01X+011849Y+049533X0200Y         S2      
017m0218            VIA   -    M      A06X+011849Y+049533X0260Y         S2      
017m0218                  -    MD0100PA00X+011849Y+049533                       
327m0218            U317  -2          A01X+012085Y+050063X0070Y0320R180 S1      
327m0218            R4938 -1   M      A01X+011900Y+049058X0198Y0197R270 S1      
327m0218            R4936 -2          A01X+011900Y+048158X0198Y0197R090 S1      
327FAN_4_SS         PC40  -1          A06X+001500Y+025369X0198Y0197R270 S2      
327FAN_4_SS         PU6   -21         A06X+001772Y+024152X0070Y0360     S2      
317FAN_4_SS         VIA   -    M      A01X+001479Y+024772X0300Y    R180 S1      
017FAN_4_SS         VIA   -    M      A06X+001479Y+024772X0200Y    R180 S1      
017FAN_4_SS               -    MD0100PA00X+001479Y+024772                       
327FAN_5_PWM_IL     R5201 -2          A01X+005812Y+042038X0198Y0197     S1      
327FAN_5_PWM_IL     VIA   -    M      A01X+007668Y+042600X0300Y         S1      
327FAN_5_PWM_IL     U325  -1          A01X+009626Y+041356X0280Y0360R090 S1      
327m0219            VIA   -    M      A01X+011491Y+049549X0300Y         S1      
327m0219            U317  -1          A01X+011928Y+050063X0070Y0320R180 S1      
327m0219            R4939 -1   M      A01X+011350Y+049058X0198Y0197R270 S1      
327m0219            R4940 -2          A01X+011350Y+048158X0198Y0197R090 S1      
317FAN_4_CLREF      VIA   -    M      A01X+002217Y+024615X0300Y         S1      
017FAN_4_CLREF      VIA   -    M      A06X+002217Y+024615X0200Y         S1      
017FAN_4_CLREF            -    MD0100PA00X+002217Y+024615                       
327FAN_4_CLREF      PC3122-2          A06X+002292Y+025750X0198Y0197     S2      
327FAN_4_CLREF      PU6   -24         A06X+002244Y+024152X0070Y0360     S2      
327FAN_4_CLREF      PR53  -1   M      A06X+002292Y+025350X0198Y0197R180 S2      
327m0220            VIA   -    M      A01X+010674Y+050878X0300Y         S1      
327m0220            R4941 -1   M      A01X+010208Y+051750X0198Y0197R180 S1      
327m0220            R4942 -2          A01X+010208Y+052150X0198Y0197     S1      
327m0220            U317  -25         A01X+011613Y+050850X0070Y0320R090 S1      
327FAN_4_PWM_OL     U323  -2          A01X+009926Y+007144X0280Y0360R090 S1      
327FAN_4_PWM_OL     R5128 -1          A01X+005762Y+005634X0198Y0197R180 S1      
327FAN_4_PWM_OL     VIA   -    M      A01X+009308Y+007200X0300Y         S1      
327m0221            VIA   -    M      A01X+012207Y+049524X0300Y         S1      
327m0221            U317  -3          A01X+012242Y+050063X0070Y0320R180 S1      
327m0221            R4779 -2   M      A01X+012450Y+049058X0198Y0197R090 S1      
327m0221            R4782 -2          A01X+012450Y+048158X0198Y0197R090 S1      
327FAN_4_PWM_IL     U323  -1          A01X+009926Y+007656X0280Y0360R090 S1      
327FAN_4_PWM_IL     R5130 -2          A01X+005812Y+007534X0198Y0197     S1      
327FAN_4_PWM_IL     VIA   -    M      A01X+007388Y+008077X0300Y         S1      
327SMB_FAN4_SCL_R   R5131 -2          A01X+005492Y+007969X0198Y0197R180 S1      
317SMB_FAN4_SCL_R   J5    -6    D0380PA00X+003425Y+006461X0540Y    R270 S3      
327SMB_FAN4_SCL_R   VIA   -    M      A01X+004818Y+007388X0300Y         S1      
327P52V_FAN_7_EN    R5425 -2          A01X+004399Y+100450X0198Y0197R180 S1      
327P52V_FAN_7_EN    U385  -4          A06X+004477Y+100494X0130Y0460R090 S2      
317P52V_FAN_7_EN    VIA   -    M      A01X+003906Y+100500X0300Y         S1      
017P52V_FAN_7_EN    VIA   -    M      A06X+003906Y+100500X0200Y         S1      
017P52V_FAN_7_EN          -    MD0100PA00X+003906Y+100500                       
327FAN_7_PWM        R5595 -1          A01X+005692Y+053100X0180Y0200     S1      
327FAN_7_PWM        R5619 -1   M      A01X+005692Y+053100X0180Y0200R180 S1      
317FAN_7_PWM        VIA   -    MD0100PA00X+005692Y+053350X0200Y         S0      
327FAN_7_PWM        R5522 -2   M      A01X+011550Y+114842X0198Y0197R270 S1      
317FAN_7_PWM        VIA   -    M      A01X+006423Y+111527X0300Y         S1      
017FAN_7_PWM        VIA   -    M      A06X+006423Y+111527X0200Y         S1      
017FAN_7_PWM              -    MD0100PA00X+006423Y+111527                       
327FAN_7_PWM        U402  -2          A01X+011550Y+114374X0160Y0200     S1      
327m0222            R4988 -2          A01X+010650Y+005312X0198Y0197R270 S1      
327m0222            R4969 -2   M      A01X+010250Y+005312X0198Y0197R270 S1      
327m0222            GF1   -S8         A01X+009799Y+001713X0320Y1970     S1      
327m0223            R5321 -2          A01X+007060Y+119100X0280Y0320R090 S1      
327m0223            R5323 -1   M      A01X+006942Y+119650X0180Y0200R180 S1      
327m0223            C2059 -1   M      A01X+006500Y+119692X0198Y0197R090 S1      
317m0223            VIA   -    M      A01X+006484Y+119400X0200Y         S2      
017m0223            VIA   -    M      A06X+006484Y+119400X0260Y         S2      
017m0223                  -    MD0100PA00X+006484Y+119400                       
327m0223            D144  -1          A01X+006484Y+119065X0320Y0340     S1      
327P52V_FAN_6_EN    R5423 -2          A01X+003587Y+099550X0198Y0197     S1      
317P52V_FAN_6_EN    VIA   -    M      A01X+004050Y+099500X0300Y    R180 S1      
017P52V_FAN_6_EN    VIA   -    M      A06X+004050Y+099500X0200Y    R180 S1      
017P52V_FAN_6_EN          -    MD0100PA00X+004050Y+099500                       
327P52V_FAN_6_EN    U383  -4          A06X+003508Y+099506X0130Y0460R270 S2      
327m0224            R4968 -2          A01X+009600Y+005312X0198Y0197R270 S1      
327m0224            GF1   -S7         A01X+009299Y+001713X0320Y1970     S1      
327m0224            R4989 -2   M      A01X+009150Y+005312X0198Y0197R270 S1      
327P52V_FAN_5_EN    R5356 -2          A01X+004349Y+027773X0198Y0197R180 S1      
317P52V_FAN_5_EN    VIA   -    M      A01X+003838Y+028012X0200Y         S2      
017P52V_FAN_5_EN    VIA   -    M      A06X+003838Y+028012X0260Y         S2      
017P52V_FAN_5_EN          -    MD0100PA00X+003838Y+028012                       
327P52V_FAN_5_EN    U361  -4          A06X+004427Y+027817X0130Y0460R090 S2      
327FAN_6_PWM        R5591 -1          A01X+005692Y+051100X0180Y0200     S1      
327FAN_6_PWM        R5615 -1   M      A01X+005692Y+051100X0180Y0200R180 S1      
327FAN_6_PWM        VIA   -    M      A01X+009598Y+080597X0300Y         S1      
317FAN_6_PWM        VIA   -    MD0100PA00X+005692Y+051350X0200Y         S0      
317FAN_6_PWM        VIA   -    MD0100PA00X+005280Y+081350X0200Y         S0      
327FAN_6_PWM        R5521 -2   M      A01X+011450Y+078542X0198Y0197R270 S1      
327FAN_6_PWM        U401  -2          A01X+011450Y+078074X0160Y0200     S1      
327P52V_FAN_4_EN    R5354 -2          A01X+003587Y+026873X0198Y0197     S1      
317P52V_FAN_4_EN    VIA   -    M      A01X+004186Y+026564X0300Y    R180 S1      
017P52V_FAN_4_EN    VIA   -    M      A06X+004186Y+026564X0200Y    R180 S1      
017P52V_FAN_4_EN          -    MD0100PA00X+004186Y+026564                       
327P52V_FAN_4_EN    U359  -4          A06X+003508Y+026829X0130Y0460R270 S2      
327P52V_FAN_3_EN    R506  -2          A01X+015956Y+026873X0198Y0197     S1      
317P52V_FAN_3_EN    VIA   -    M      A01X+016501Y+026829X0200Y    R180 S2      
017P52V_FAN_3_EN    VIA   -    M      A06X+016501Y+026829X0260Y    R180 S2      
017P52V_FAN_3_EN          -    MD0100PA00X+016501Y+026829                       
327P52V_FAN_3_EN    U74   -4          A06X+015877Y+026829X0130Y0460R270 S2      
327P52V_FAN_2_EN    R5421 -2          A01X+015278Y+027773X0198Y0197R180 S1      
317P52V_FAN_2_EN    VIA   -    M      A01X+014750Y+027823X0200Y         S2      
017P52V_FAN_2_EN    VIA   -    M      A06X+014750Y+027823X0260Y         S2      
017P52V_FAN_2_EN          -    MD0100PA00X+014750Y+027823                       
327P52V_FAN_2_EN    U381  -4          A06X+015357Y+027817X0130Y0460R090 S2      
327P52V_FAN_1_EN    R5419 -2          A01X+015956Y+099865X0198Y0197     S1      
317P52V_FAN_1_EN    VIA   -    M      A01X+016460Y+099865X0200Y    R180 S2      
017P52V_FAN_1_EN    VIA   -    M      A06X+016460Y+099865X0260Y    R180 S2      
017P52V_FAN_1_EN          -    MD0100PA00X+016460Y+099865                       
327P52V_FAN_1_EN    U379  -4          A06X+015877Y+099821X0130Y0460R270 S2      
327P52V_FAN_0_EN    R5417 -2          A01X+015278Y+100450X0198Y0197R180 S1      
317P52V_FAN_0_EN    VIA   -    M      A01X+014664Y+100736X0300Y         S1      
017P52V_FAN_0_EN    VIA   -    M      A06X+014664Y+100736X0200Y         S1      
017P52V_FAN_0_EN          -    MD0100PA00X+014664Y+100736                       
327P52V_FAN_0_EN    U377  -4          A06X+015357Y+100494X0130Y0460R090 S2      
327SMB_FAN7_SCL_R   VIA   -    M      A01X+004940Y+115300X0300Y         S1      
317SMB_FAN7_SCL_R   J8    -6    D0380PA00X+003425Y+115476X0540Y    R270 S3      
327SMB_FAN7_SCL_R   R5243 -2          A01X+005492Y+115200X0198Y0197R180 S1      
327FAN_0_PRESENT    R5416 -2          A01X+016943Y+101050X0198Y0197     S1      
317FAN_0_PRESENT    VIA   -    MD0100PA00X+016936Y+101300X0200Y         S0      
327FAN_0_PRESENT    U394  -4          A06X+017290Y+101054X0240Y0240R270 S2      
317FAN_0_PRESENT    VIA   -    M      A01X+019200Y+124050X0200Y         S2      
017FAN_0_PRESENT    VIA   -    M      A06X+019200Y+124050X0260Y         S2      
017FAN_0_PRESENT          -    MD0100PA00X+019200Y+124050                       
327FAN_0_PRESENT    U405  -G          A01X+019056Y+123515X0240Y0320R180 S1      
327FAN_0_PRESENT    R5647 -1   M      A01X+018958Y+124050X0198Y0197R180 S1      
327SMB_FAN6_SCL_R   VIA   -    M      A01X+004710Y+078970X0300Y         S1      
317SMB_FAN6_SCL_R   J7    -6    D0380PA00X+003425Y+079138X0540Y    R270 S3      
327SMB_FAN6_SCL_R   R5223 -2          A01X+005492Y+078811X0198Y0197R180 S1      
327m0225            R5316 -2   M      A01X+007160Y+077800X0280Y0320R090 S1      
327m0225            R5318 -1          A01X+007200Y+077308X0180Y0200R090 S1      
327m0225            C2046 -1   M      A01X+006658Y+077850X0198Y0197R180 S1      
327m0225            D138  -1          A01X+006484Y+077226X0320Y0340     S1      
317m0225            VIA   -    M      A01X+006600Y+077600X0200Y         S2      
017m0225            VIA   -    M      A06X+006600Y+077600X0260Y         S2      
017m0225                  -    MD0100PA00X+006600Y+077600                       
C                                                                               
C  ****************************************                                     
C      DUMMY NET PINS & VIAS ON THE BOARD                                       
C  ****************************************                                     
C                                                                               
327N/C                    -           A06X+006300Y+123700X0390Y         S2      
327N/C                    -           A06X+018790Y+067520X0390Y         S2      
327N/C                    -           A06X+012000Y+026750X0390Y         S2      
327N/C                    -           A01X+015800Y+001750X0390Y         S1      
327N/C                    -           A01X+009550Y+038800X0390Y         S1      
317N/C              H15   -1    D1250UA00X+002000Y+130700X1250Y         S3      
317N/C              H14   -1    D1250UA00X+017850Y+001750X1250Y         S3      
317N/C              H13   -1    D1250UA00X+004400Y+001750X1250Y         S3      
327N/C                    -           A01X+016696Y+130423X0390Y         S1      
317N/C              J8    -16   D0380PA00X+003425Y+119413X0540Y    R270 S3      
317N/C              J8    -15   D0380PA00X+002638Y+119413X0540Y    R270 S3      
317N/C              J8    -H1   D0590UA00X+003032Y+113154X0590Y    R270 S3      
317N/C              J7    -16   D0380PA00X+003425Y+083075X0540Y    R270 S3      
317N/C              J7    -15   D0380PA00X+002638Y+083075X0540Y    R270 S3      
317N/C              J7    -H1   D0590UA00X+003032Y+076815X0590Y    R270 S3      
317N/C              J6    -16   D0380PA00X+003425Y+046736X0540Y    R270 S3      
317N/C              J6    -15   D0380PA00X+002638Y+046736X0540Y    R270 S3      
317N/C              J6    -H1   D0590UA00X+003032Y+040476X0590Y    R270 S3      
317N/C              J5    -16   D0380PA00X+003425Y+010398X0540Y    R270 S3      
317N/C              J5    -15   D0380PA00X+002638Y+010398X0540Y    R270 S3      
317N/C              J5    -H1   D0590UA00X+003032Y+004138X0590Y    R270 S3      
317N/C              J4    -16   D0380PA00X+016929Y+004886X0540Y    R090 S3      
317N/C              J4    -15   D0380PA00X+017716Y+004886X0540Y    R090 S3      
317N/C              J4    -H1   D0590UA00X+017323Y+011146X0590Y    R090 S3      
317N/C              J3    -16   D0380PA00X+016929Y+041224X0540Y    R090 S3      
317N/C              J3    -15   D0380PA00X+017716Y+041224X0540Y    R090 S3      
317N/C              J3    -H1   D0590UA00X+017323Y+047484X0590Y    R090 S3      
317N/C              J2    -16   D0380PA00X+016929Y+077563X0540Y    R090 S3      
317N/C              J2    -15   D0380PA00X+017716Y+077563X0540Y    R090 S3      
317N/C              J2    -H1   D0590UA00X+017323Y+083823X0590Y    R090 S3      
317N/C              J1    -16   D0380PA00X+016929Y+113902X0540Y    R090 S3      
317N/C              J1    -15   D0380PA00X+017716Y+113902X0540Y    R090 S3      
317N/C              J1    -H1   D0590UA00X+017323Y+120161X0590Y    R090 S3      
C                                                                               
C  End-of-Job                                                                   
C                                                                               
999                                                                             
